G04 ================== begin FILE IDENTIFICATION RECORD ==================*
G04 Layout Name:  x887571-005_osp.brd*
G04 Film Name:    lyr4*
G04 File Format:  Gerber RS274X*
G04 File Origin:  Cadence Allegro 16.3-S036*
G04 Origin Date:  Thu Jul 03 00:06:57 2014*
G04 *
G04 Layer:  VIA CLASS/LYR4*
G04 Layer:  PIN/LYR4*
G04 Layer:  ETCH/LYR4*
G04 Layer:  DRAWING FORMAT/COMMON TEXT*
G04 Layer:  BOARD GEOMETRY/LAYER 4 TEXT*
G04 *
G04 Offset:    (0.0000 0.0000)*
G04 Mirror:    No*
G04 Mode:      Positive*
G04 Rotation:  0*
G04 FullContactRelief:  No*
G04 UndefLineWidth:     4.0000*
G04 ================== end FILE IDENTIFICATION RECORD ====================*
%FSLAX25Y25*MOIN*%
%IR0*IPPOS*OFA0.00000B0.00000*MIA0B0*SFA1.00000B1.00000*%
%ADD10C,.022*%
%ADD12C,.05*%
%ADD11C,.032*%
%ADD15C,.044*%
%ADD16C,.027*%
%ADD13C,.054*%
%ADD14C,.079*%
%ADD17C,.01*%
%ADD18C,.02*%
%ADD19C,.012*%
%ADD20C,.013*%
%ADD21C,.015*%
%ADD22C,.004*%
%ADD23C,.005*%
%ADD24C,.006*%
%ADD25C,.0051*%
%ADD26C,.007*%
%ADD27C,.008*%
%ADD28C,.032*%
%ADD29C,.08*%
%ADD34C,.063*%
%ADD39C,.046*%
%ADD33C,.064*%
%ADD30C,.073*%
%ADD38C,.091001*%
%ADD35C,.077*%
%ADD32C,.098*%
%ADD31C,.099*%
%ADD37C,.154001*%
%ADD36C,.186001*%
G75*
%LPD*%
G75*
G36*
G01X-1137390Y-112736D02*
X-1137395Y-112633D01*
G03X-1145085I-3845J-202D01*
G01X-1145150Y-113875D01*
Y-119790D01*
X-1145200D01*
Y-119850D01*
X-1202500D01*
X-1205925Y-123275D01*
X-1205900Y-123300D01*
Y-146130D01*
X-1208158D01*
G02X-1208539Y-145306I0J500D01*
G03X-1215477I-3469J2944D01*
G02X-1215858Y-146130I-381J-324D01*
G01X-1217656D01*
X-1217701Y-146112D01*
G03X-1218879I-589J-1488D01*
G01X-1218924Y-146130D01*
X-1225456D01*
X-1225501Y-146112D01*
G03X-1226679I-589J-1488D01*
G01X-1226724Y-146130D01*
X-1247087D01*
G02X-1247546Y-145432I0J500D01*
G03X-1250486I-1470J632D01*
G02X-1250945Y-146130I-459J-198D01*
G01X-1254644D01*
G03X-1255903Y-145151I-1481J-605D01*
G02X-1256332Y-144615I69J495D01*
G03X-1256333Y-144259I-2093J172D01*
G02X-1255904Y-143720I498J44D01*
G03X-1257725Y-142135I-221J1585D01*
G01Y-142147D01*
X-1257751Y-142407D01*
X-1258023Y-142381D01*
X-1258034Y-142379D01*
G03X-1258202Y-142354I-391J-2063D01*
G01X-1258379Y-142335D01*
X-1261672D01*
X-1261849Y-142354D01*
G03X-1261897Y-142360I223J-2088D01*
G02X-1262461Y-141885I-65J496D01*
G03X-1264163Y-143547I-1599J-65D01*
G02X-1263700Y-144122I-32J-499D01*
G03X-1263718Y-144615I2075J-320D01*
G02X-1264147Y-145151I-498J-41D01*
G03X-1265406Y-146130I222J-1585D01*
G01X-1267040D01*
X-1270590Y-149680D01*
X-1271134D01*
X-1271312Y-149699D01*
G03X-1271490Y-149726I224J-2088D01*
G02X-1271788Y-149480I-48J245D01*
G03X-1274717Y-150371I-1600J0D01*
G02X-1275132Y-151150I-415J-279D01*
G01X-1277030D01*
X-1277090Y-151210D01*
Y-168320D01*
X-1281941D01*
G03X-1282480Y-176283I-540J-3963D01*
G01X-1282230D01*
Y-183700D01*
X-1455500D01*
Y-74400D01*
X-1465900Y-64000D01*
X-1472777D01*
X-1472827Y-63814D01*
G03X-1480559I-3866J-1026D01*
G01X-1480609Y-64000D01*
X-1614300D01*
X-1625550Y-52750D01*
Y-31050D01*
X-1625500Y-31000D01*
Y-27003D01*
X-1621002Y-22505D01*
X-1620891Y-22510D01*
G03X-1617131Y-18937I182J3573D01*
G01Y16175D01*
X-1616226Y17080D01*
X-1461294D01*
X-1460389Y16175D01*
Y-14409D01*
G03X-1452283Y-22515I8106J0D01*
G01X-1448346D01*
G03X-1440241Y-14409I0J8106D01*
G01Y9213D01*
G02X-1432598Y16855I7643J0D01*
G01X-347025D01*
X-344700Y14530D01*
Y-66900D01*
X-380350Y-102550D01*
Y-106150D01*
X-415700Y-141500D01*
Y-170021D01*
G03Y-174546I3298J-2263D01*
G01Y-178500D01*
X-417200Y-180000D01*
X-585400D01*
X-585400Y-69900D01*
X-596295Y-59005D01*
X-633905D01*
X-647400Y-72500D01*
X-707200D01*
X-725800Y-91100D01*
X-751000D01*
Y-181100D01*
X-972868D01*
Y-179784D01*
X-972841Y-179731D01*
G03X-972868Y-177383I-2277J1148D01*
G01Y-174271D01*
G03Y-171871I-2250J1200D01*
G01Y-169768D01*
G02X-973040Y-169037I236J441D01*
G03Y-166081I-2078J1478D01*
G02X-972868Y-165350I407J290D01*
G01Y-163247D01*
G03Y-160847I-2250J1200D01*
G01Y-157735D01*
G03Y-155335I-2250J1200D01*
G01Y-153232D01*
G02X-973040Y-152502I236J441D01*
G03Y-149546I-2078J1478D01*
G02X-972868Y-148815I407J290D01*
G01Y-146712D01*
G03Y-144312I-2250J1200D01*
G01Y-141200D01*
G03Y-138800I-2250J1200D01*
G01Y-136697D01*
G02X-973040Y-135966I236J441D01*
G03X-977196I-2078J1478D01*
G02X-977368Y-136697I-407J-290D01*
G01Y-138800D01*
G03Y-141200I2250J-1200D01*
G01Y-144312D01*
G03Y-146712I2250J-1200D01*
G01Y-148815D01*
G02X-977196Y-149546I-236J-441D01*
G03Y-152502I2078J-1478D01*
G02X-977368Y-153232I-407J-290D01*
G01Y-155335D01*
G03Y-157735I2250J-1200D01*
G01Y-160847D01*
G03Y-163247I2250J-1200D01*
G01Y-165350D01*
G02X-977196Y-166081I-236J-441D01*
G03Y-169037I2078J-1478D01*
G02X-977368Y-169768I-407J-290D01*
G01Y-171871D01*
G03Y-174271I2250J-1200D01*
G01Y-177383D01*
G03X-977395Y-179731I2250J-1200D01*
G01X-977368Y-179784D01*
Y-181100D01*
X-980410D01*
G02X-980833Y-180334I0J500D01*
G03X-980914Y-177498I-2159J1357D01*
G02X-980742Y-176768I407J290D01*
G01Y-174665D01*
G03Y-172265I-2250J1200D01*
G01Y-169153D01*
G03Y-166753I-2250J1200D01*
G01Y-164650D01*
G02X-980914Y-163919I236J441D01*
G03Y-160963I-2078J1478D01*
G02X-980742Y-160232I407J290D01*
G01Y-158129D01*
G03Y-155729I-2250J1200D01*
G01Y-152617D01*
G03Y-150217I-2250J1200D01*
G01Y-148114D01*
G02X-980914Y-147383I236J441D01*
G03Y-144428I-2078J1478D01*
G02X-980742Y-143697I407J290D01*
G01Y-141594D01*
G03Y-139194I-2250J1200D01*
G01Y-136082D01*
G03Y-133682I-2250J1200D01*
G01Y-131579D01*
G02X-980914Y-130848I236J441D01*
G03X-985070I-2078J1478D01*
G02X-985242Y-131579I-407J-290D01*
G01Y-133682D01*
G03Y-136082I2250J-1200D01*
G01Y-139194D01*
G03Y-141594I2250J-1200D01*
G01Y-143697D01*
G02X-985070Y-144428I-236J-441D01*
G03Y-147383I2078J-1478D01*
G02X-985242Y-148114I-407J-290D01*
G01Y-150217D01*
G03Y-152617I2250J-1200D01*
G01Y-155729D01*
G03Y-158129I2250J-1200D01*
G01Y-160232D01*
G02X-985070Y-160963I-236J-441D01*
G03Y-163919I2078J-1478D01*
G02X-985242Y-164650I-407J-290D01*
G01Y-166753D01*
G03Y-169153I2250J-1200D01*
G01Y-172265D01*
G03Y-174665I2250J-1200D01*
G01Y-176768D01*
G02X-985070Y-177498I-236J-441D01*
G03X-985151Y-180334I2078J-1478D01*
G02X-985574Y-181100I-423J-266D01*
G01X-988579D01*
G02X-988954Y-180269I0J500D01*
G03X-989774Y-176279I-1913J1687D01*
G02Y-175375I214J452D01*
G03Y-170767I-1093J2304D01*
G02Y-169863I214J452D01*
G03X-988788Y-166081I-1093J2304D01*
G02X-988616Y-165350I407J290D01*
G01Y-163247D01*
G03Y-160847I-2250J1200D01*
G01Y-157735D01*
G03Y-155335I-2250J1200D01*
G01Y-153232D01*
G02X-988788Y-152502I236J441D01*
G03Y-149546I-2078J1478D01*
G02X-988616Y-148815I407J290D01*
G01Y-146712D01*
G03Y-144312I-2250J1200D01*
G01Y-141200D01*
G03Y-138800I-2250J1200D01*
G01Y-136697D01*
G02X-988788Y-135966I236J441D01*
G03X-992944I-2078J1478D01*
G02X-993116Y-136697I-407J-290D01*
G01Y-138800D01*
G03Y-141200I2250J-1200D01*
G01Y-144312D01*
G03Y-146712I2250J-1200D01*
G01Y-148815D01*
G02X-992944Y-149546I-236J-441D01*
G03Y-152502I2078J-1478D01*
G02X-993116Y-153232I-407J-290D01*
G01Y-155335D01*
G03Y-157735I2250J-1200D01*
G01Y-160847D01*
G03Y-163247I2250J-1200D01*
G01Y-165350D01*
G02X-992944Y-166081I-236J-441D01*
G03X-991959Y-169863I2078J-1478D01*
G02Y-170767I-214J-452D01*
G03Y-175375I1093J-2304D01*
G02Y-176279I-214J-452D01*
G03X-992779Y-180269I1093J-2304D01*
G02X-993154Y-181100I-375J-331D01*
G01X-996158D01*
G02X-996581Y-180334I0J500D01*
G03X-997648Y-176672I-2159J1357D01*
G02Y-175769I214J452D01*
G03Y-171160I-1093J2304D01*
G02Y-170257I214J452D01*
G03Y-165649I-1093J2304D01*
G02Y-164745I214J452D01*
G03X-996662Y-160963I-1093J2304D01*
G02X-996490Y-160232I407J290D01*
G01Y-158129D01*
G03Y-155729I-2250J1200D01*
G01Y-152617D01*
G03Y-150217I-2250J1200D01*
G01Y-148114D01*
G02X-996662Y-147383I236J441D01*
G03Y-144428I-2078J1478D01*
G02X-996490Y-143697I407J290D01*
G01Y-141594D01*
G03Y-139194I-2250J1200D01*
G01Y-136082D01*
G03Y-133682I-2250J1200D01*
G01Y-131579D01*
G02X-996662Y-130848I236J441D01*
G03X-1000818I-2078J1478D01*
G02X-1000990Y-131579I-407J-290D01*
G01Y-133682D01*
G03Y-136082I2250J-1200D01*
G01Y-139194D01*
G03Y-141594I2250J-1200D01*
G01Y-143697D01*
G02X-1000818Y-144428I-236J-441D01*
G03Y-147383I2078J-1478D01*
G02X-1000990Y-148114I-407J-290D01*
G01Y-150217D01*
G03Y-152617I2250J-1200D01*
G01Y-155729D01*
G03Y-158129I2250J-1200D01*
G01Y-160232D01*
G02X-1000818Y-160963I-236J-441D01*
G03X-999833Y-164745I2078J-1478D01*
G02Y-165649I-214J-452D01*
G03Y-170257I1093J-2304D01*
G02Y-171160I-214J-452D01*
G03Y-175769I1093J-2304D01*
G02Y-176672I-214J-452D01*
G03X-1000899Y-180334I1093J-2304D01*
G02X-1001322Y-181100I-423J-266D01*
G01X-1004364D01*
Y-179784D01*
X-1004337Y-179731D01*
G03X-1004364Y-177383I-2277J1148D01*
G01Y-174271D01*
G03Y-171871I-2250J1200D01*
G01Y-169768D01*
G02X-1004536Y-169037I236J441D01*
G03Y-166081I-2078J1478D01*
G02X-1004364Y-165350I407J290D01*
G01Y-163247D01*
G03Y-160847I-2250J1200D01*
G01Y-157735D01*
G03Y-155335I-2250J1200D01*
G01Y-153232D01*
G02X-1004536Y-152502I236J441D01*
G03Y-149546I-2078J1478D01*
G02X-1004364Y-148815I407J290D01*
G01Y-146712D01*
G03Y-144312I-2250J1200D01*
G01Y-141200D01*
G03Y-138800I-2250J1200D01*
G01Y-136697D01*
G02X-1004536Y-135966I236J441D01*
G03X-1008692I-2078J1478D01*
G02X-1008864Y-136697I-407J-290D01*
G01Y-138800D01*
G03Y-141200I2250J-1200D01*
G01Y-144312D01*
G03Y-146712I2250J-1200D01*
G01Y-148815D01*
G02X-1008692Y-149546I-236J-441D01*
G03Y-152502I2078J-1478D01*
G02X-1008864Y-153232I-407J-290D01*
G01Y-155335D01*
G03Y-157735I2250J-1200D01*
G01Y-160847D01*
G03Y-163247I2250J-1200D01*
G01Y-165350D01*
G02X-1008692Y-166081I-236J-441D01*
G03Y-169037I2078J-1478D01*
G02X-1008864Y-169768I-407J-290D01*
G01Y-171871D01*
G03Y-174271I2250J-1200D01*
G01Y-177383D01*
G03X-1008891Y-179731I2250J-1200D01*
G01X-1008864Y-179784D01*
Y-181100D01*
X-1011906D01*
G02X-1012330Y-180334I0J500D01*
G03X-1012410Y-177498I-2159J1357D01*
G02X-1012238Y-176768I407J290D01*
G01Y-174665D01*
G03Y-172265I-2250J1200D01*
G01Y-169153D01*
G03Y-166753I-2250J1200D01*
G01Y-164650D01*
G02X-1012410Y-163919I236J441D01*
G03Y-160963I-2078J1478D01*
G02X-1012238Y-160232I407J290D01*
G01Y-158129D01*
G03Y-155729I-2250J1200D01*
G01Y-152617D01*
G03Y-150217I-2250J1200D01*
G01Y-148114D01*
G02X-1012410Y-147383I236J441D01*
G03Y-144428I-2078J1478D01*
G02X-1012238Y-143697I407J290D01*
G01Y-141594D01*
G03Y-139194I-2250J1200D01*
G01Y-136082D01*
G03Y-133682I-2250J1200D01*
G01Y-131579D01*
G02X-1012410Y-130848I236J441D01*
G03X-1016566I-2078J1478D01*
G02X-1016738Y-131579I-407J-290D01*
G01Y-133682D01*
G03Y-136082I2250J-1200D01*
G01Y-139194D01*
G03Y-141594I2250J-1200D01*
G01Y-143697D01*
G02X-1016566Y-144428I-236J-441D01*
G03Y-147383I2078J-1478D01*
G02X-1016738Y-148114I-407J-290D01*
G01Y-150217D01*
G03Y-152617I2250J-1200D01*
G01Y-155729D01*
G03Y-158129I2250J-1200D01*
G01Y-160232D01*
G02X-1016566Y-160963I-236J-441D01*
G03Y-163919I2078J-1478D01*
G02X-1016738Y-164650I-407J-290D01*
G01Y-166753D01*
G03Y-169153I2250J-1200D01*
G01Y-172265D01*
G03Y-174665I2250J-1200D01*
G01Y-176768D01*
G02X-1016566Y-177498I-236J-441D01*
G03X-1016647Y-180334I2078J-1478D01*
G02X-1017070Y-181100I-423J-266D01*
G01X-1075300D01*
X-1075800Y-180600D01*
Y-157400D01*
X-1075890D01*
Y-114040D01*
X-1080845D01*
G02X-1081339Y-113459I0J500D01*
G03X-1088937I-3799J624D01*
G02X-1089430Y-114040I-493J-81D01*
G01X-1136020D01*
Y-113880D01*
X-1137390D01*
Y-112736D01*
G37*
G36*
G01X-1201000Y-184000D02*
Y-176553D01*
X-1200997Y-176535D01*
G03Y-176065I-1583J235D01*
G01X-1201000Y-176047D01*
Y-125000D01*
X-1199500Y-123500D01*
X-1151100D01*
X-1146900Y-127700D01*
Y-150500D01*
X-1135900Y-161500D01*
X-1078700D01*
Y-184000D01*
X-1201000D01*
G37*
G36*
G01X-897784Y-186850D02*
X-881784D01*
Y-184850D01*
X-897784D01*
X-903784D01*
Y-186850D01*
X-897784D01*
G37*
G36*
G01X-329500Y-183400D02*
Y-181216D01*
G02X-328661Y-180849I500J0D01*
G03X-324851Y-177499I1731J1872D01*
G02X-324681Y-176769I407J290D01*
G01Y-174668D01*
G03Y-172261I-2248J1203D01*
G01Y-169156D01*
G03Y-166750I-2248J1203D01*
G01Y-164649D01*
G02X-324851Y-163919I237J440D01*
G03X-324851Y-160963I-2078J1478D01*
G02X-324681Y-160233I407J290D01*
G01Y-158132D01*
G03Y-155726I-2248J1203D01*
G01Y-152621D01*
G03Y-150214I-2248J1203D01*
G01Y-148113D01*
G02X-324851Y-147383I237J440D01*
G03Y-144428I-2078J1478D01*
G02X-324681Y-143698I407J290D01*
G01Y-141597D01*
G03Y-139190I-2248J1203D01*
G01Y-136085D01*
G03Y-133679I-2248J1203D01*
G01Y-131578D01*
G02X-324851Y-130848I237J440D01*
G03X-328661Y-127498I-2078J1478D01*
G02X-329500Y-127131I-339J367D01*
G01Y-125900D01*
X-275900D01*
Y-141114D01*
X-275908Y-141145D01*
G03Y-143579I4746J-1217D01*
G01X-275900Y-143610D01*
Y-159600D01*
X-194000D01*
Y-183400D01*
X-329500D01*
G37*
G36*
G01X-149270Y14900D02*
X-62700D01*
Y-184500D01*
X-161600D01*
Y15000D01*
X-149370D01*
X-149270Y14900D01*
G37*
%LPC*%
G75*
G36*
G01X-1054898Y-158465D02*
G03X-1054946Y-157514I-177J468D01*
G02X-1048280I3333J12514D01*
G03X-1048328Y-158465I129J-483D01*
G02X-1054898I-3285J-8701D01*
G37*
G36*
G01X-1011074Y-56397D02*
G02X-1014202I-1564J337D01*
G01X-1014245Y-56200D01*
X-1018700D01*
Y-45550D01*
X-1012969D01*
X-1012416Y-45293D01*
X-1011746Y-45550D01*
X-1004110D01*
X-1003558Y-45293D01*
X-1002888Y-45550D01*
X-988100D01*
Y-56200D01*
X-999560D01*
X-1000094Y-56464D01*
X-1000830Y-56200D01*
X-1002173D01*
X-1002216Y-56397D01*
G02X-1005344I-1564J337D01*
G01X-1005386Y-56200D01*
X-1008419D01*
X-1008952Y-56464D01*
X-1009688Y-56200D01*
X-1011031D01*
X-1011074Y-56397D01*
G37*
G36*
G01X-996593Y-41454D02*
G02X-1003425Y-44825I-6753J5079D01*
G01X-1003543Y-44824D01*
X-1003662Y-44820D01*
G02X-995224Y-38704I315J8444D01*
G03X-994633Y-39329I481J-138D01*
G02X-995738Y-41549I353J-1561D01*
G03X-996593Y-41454I-456J-206D01*
G37*
G36*
G01X-965394Y-71300D02*
X-965645Y-71424D01*
X-965992Y-71300D01*
X-974800D01*
Y-60800D01*
X-970282D01*
X-969109Y-60253D01*
X-967685Y-60800D01*
X-961424D01*
X-960251Y-60253D01*
X-958827Y-60800D01*
X-958165D01*
X-958127Y-60595D01*
G02X-957891Y-60007I1574J-290D01*
G03X-958182Y-59248I-418J275D01*
G02X-959092Y-56786I404J1548D01*
G03X-959502Y-56000I-410J286D01*
G01X-964707D01*
X-965645Y-56464D01*
X-966939Y-56000D01*
X-974400D01*
Y-45750D01*
X-970090D01*
X-969109Y-45293D01*
X-967918Y-45750D01*
X-967015D01*
X-966969Y-45557D01*
G02X-963854I1558J-365D01*
G01X-963809Y-45750D01*
X-961232D01*
X-961099Y-45688D01*
G03X-961239Y-44740I-211J453D01*
G02X-955767Y-43666I1200J8364D01*
G03X-955762Y-44532I253J-431D01*
G02X-954996Y-45557I-792J-1390D01*
G01X-954950Y-45750D01*
X-945550D01*
Y-56000D01*
X-955848D01*
X-956198Y-56173D01*
G03X-956406Y-56878I221J-448D01*
G02X-956441Y-58579I-1373J-822D01*
G03X-956150Y-59337I418J-275D01*
G02X-954980Y-60595I-404J-1548D01*
G01X-954942Y-60800D01*
X-945700D01*
Y-71300D01*
X-956535D01*
X-956787Y-71424D01*
X-957134Y-71300D01*
X-965394D01*
G37*
G36*
G01X-1450413Y-73798D02*
G02X-1451378Y-72526I-1587J-202D01*
G03X-1450687Y-72002I194J461D01*
G02X-1450693Y-71655I1587J202D01*
G03X-1451336Y-71131I-498J45D01*
G02X-1451114Y-68154I-464J1531D01*
G03X-1450400Y-67702I214J452D01*
G02X-1450399Y-67655I1600J2D01*
G03X-1451090Y-67179I-500J14D01*
G02X-1451090Y-64221I-610J1479D01*
G03X-1450400Y-63768I191J462D01*
G02X-1450366Y-63473I1600J-32D01*
G03X-1450731Y-63203I-245J51D01*
G02X-1450966Y-60292I-769J1403D01*
G03X-1450299Y-59840I167J471D01*
G02X-1449234Y-61408I1599J-60D01*
G03X-1449901Y-61860I-167J-471D01*
G02X-1449934Y-62127I-1599J61D01*
G03X-1449569Y-62397I245J-51D01*
G02X-1449410Y-65279I769J-1403D01*
G03X-1450100Y-65732I-191J-462D01*
G02X-1450101Y-65745I-1600J31D01*
G03X-1449410Y-66221I500J-14D01*
G02X-1449486Y-69146I610J-1479D01*
G03X-1450200Y-69598I-214J-452D01*
G02X-1450207Y-69745I-1600J-2D01*
G03X-1449564Y-70269I498J-45D01*
G02X-1449722Y-73274I464J-1531D01*
G03X-1450413Y-73798I-194J-461D01*
G37*
G36*
G01X-1450500Y-82159D02*
G02X-1451338Y-80793I-1599J-41D01*
G03X-1450600Y-80341I238J440D01*
G02X-1450592Y-80142I1599J41D01*
G03X-1451306Y-79642I-498J49D01*
G02X-1450408Y-78358I-694J1442D01*
G03X-1449694Y-78858I498J-49D01*
G02X-1449762Y-81707I694J-1442D01*
G03X-1450500Y-82159I-238J-440D01*
G37*
G36*
G01X-1001807Y-86692D02*
G02X-1004952I-1573J-294D01*
G03X-1005444Y-86100I-491J92D01*
G01X-1008376D01*
X-1008952Y-86385D01*
X-1009747Y-86100D01*
X-1011041D01*
X-1011089Y-86287D01*
G02X-1014187I-1549J401D01*
G01X-1014235Y-86100D01*
X-1018700D01*
Y-72650D01*
X-1015857D01*
X-1015810Y-72630D01*
G02X-1014548I631J-1470D01*
G01X-1014500Y-72650D01*
X-1014305D01*
G03X-1013908Y-71846I0J500D01*
G02X-1014158Y-71372I1270J973D01*
G01X-1014215Y-71200D01*
X-1018500D01*
Y-60650D01*
X-1013267D01*
X-1012416Y-60253D01*
X-1011383Y-60650D01*
X-1004409D01*
X-1003558Y-60253D01*
X-1002525Y-60650D01*
X-1001455D01*
X-1001404Y-60466D01*
G02X-998316I1544J-420D01*
G01X-998266Y-60650D01*
X-988050D01*
Y-71200D01*
X-999640D01*
X-1000094Y-71424D01*
X-1000720Y-71200D01*
X-1008498D01*
X-1008952Y-71424D01*
X-1009578Y-71200D01*
X-1011061D01*
X-1011118Y-71372D01*
G02X-1011368Y-71846I-1520J499D01*
G03X-1010971Y-72650I397J-304D01*
G01X-987750D01*
Y-86100D01*
X-999517D01*
X-1000094Y-86385D01*
X-1000889Y-86100D01*
X-1001316D01*
G03X-1001807Y-86692I0J-500D01*
G37*
G36*
G01X-969461Y-103260D02*
G02X-971328Y-102206I-2390J-2052D01*
G03X-970789Y-101507I83J493D01*
G02X-970871Y-101282I1458J658D01*
G01X-970922Y-101100D01*
X-974400D01*
Y-101050D01*
X-974500D01*
Y-90500D01*
X-969808D01*
X-969109Y-90174D01*
X-968262Y-90500D01*
X-967110D01*
X-967062Y-90312D01*
G02X-963961I1551J-395D01*
G01X-963913Y-90500D01*
X-960949D01*
X-960251Y-90174D01*
X-959403Y-90500D01*
X-958252D01*
X-958204Y-90312D01*
G02X-955103I1551J-395D01*
G01X-955055Y-90500D01*
X-945400D01*
Y-101050D01*
X-945600D01*
Y-101100D01*
X-956290D01*
X-956787Y-101346D01*
X-957472Y-101100D01*
X-958659D01*
X-958694Y-101309D01*
G02X-961851I-1579J260D01*
G01X-961886Y-101100D01*
X-965148D01*
X-965645Y-101346D01*
X-966330Y-101100D01*
X-967739D01*
X-967791Y-101282D01*
G02X-969141Y-102438I-1540J433D01*
G03X-969461Y-103260I59J-496D01*
G37*
G36*
G01X-1014214Y-102307D02*
G02X-1016785Y-102616I-944J-3005D01*
G03X-1016730Y-101798I-258J428D01*
G02X-1017227Y-101112I1002J1248D01*
G01X-1017288Y-100950D01*
X-1018700D01*
Y-90550D01*
X-1013222D01*
X-1012416Y-90174D01*
X-1011438Y-90550D01*
X-1009784D01*
G02X-1007073I1356J-850D01*
G01X-1004364D01*
X-1003558Y-90174D01*
X-1002580Y-90550D01*
X-1001565D01*
X-1001521Y-90355D01*
G02X-998400I1561J-351D01*
G01X-998356Y-90550D01*
X-988950D01*
Y-100950D01*
X-999293D01*
X-1000094Y-101346D01*
X-1001198Y-100950D01*
X-1008152D01*
X-1008952Y-101346D01*
X-1010056Y-100950D01*
X-1014170D01*
X-1014231Y-101112D01*
G02X-1014460Y-101525I-1498J562D01*
G03X-1014214Y-102307I396J-305D01*
G37*
G36*
G01X-445448Y-144838D02*
G02X-447341Y-147362I3519J-4611D01*
G03X-448048Y-146743I-467J180D01*
G02X-446240Y-144333I-1756J3200D01*
G03X-445448Y-144838I488J-108D01*
G37*
G36*
G01X-1315527D02*
G02X-1317420Y-147362I3519J-4611D01*
G03X-1318127Y-146743I-467J180D01*
G02X-1316318Y-144333I-1756J3200D01*
G03X-1315527Y-144838I488J-108D01*
G37*
G36*
G01X-1233471Y-136449D02*
G03X-1234009Y-136877I-43J-498D01*
G02X-1235815Y-135065I-1584J227D01*
G03X-1235385Y-134529I-69J495D01*
G02X-1235385Y-134174I2093J172D01*
G03X-1235814Y-133635I-498J44D01*
G02X-1233993Y-132050I221J1585D01*
G03X-1233695Y-132296I250J0D01*
G02X-1233516Y-132269I402J-2061D01*
G01X-1233339Y-132250D01*
X-1230046D01*
X-1229869Y-132269D01*
G02X-1229691Y-132296I-223J-2088D01*
G03X-1229393Y-132050I48J245D01*
G02X-1227572Y-133635I1600J0D01*
G03X-1228001Y-134174I69J-495D01*
G02X-1228000Y-134529I-2092J-183D01*
G03X-1227571Y-135065I498J-41D01*
G02X-1229377Y-136877I-222J-1585D01*
G03X-1229914Y-136449I-495J-71D01*
G02X-1230255Y-136451I-178J2092D01*
G01X-1230265Y-136450D01*
X-1233120D01*
X-1233130Y-136451D01*
G02X-1233471Y-136449I-162J2094D01*
G37*
G36*
G01X-1347998Y-116208D02*
G02X-1347689Y-120301I-8891J-2729D01*
G02X-1347998Y-116208I-9199J1364D01*
G37*
G36*
G01X-1139274Y-97641D02*
G03X-1139224Y-98526I255J-430D01*
G02X-1143256I-2016J-4466D01*
G03X-1143207Y-97641I-206J456D01*
G02X-1139274I1967J3310D01*
G37*
G36*
G01X-1049780Y-88943D02*
G03X-1050123Y-88281I-468J177D01*
G02X-1052953Y-87057I2447J9541D01*
G03X-1053667Y-87254I-268J-422D01*
G02X-1056558Y-84170I-2009J1014D01*
G03X-1056316Y-83470I-196J460D01*
G02X-1057217Y-81187I8640J4730D01*
G03X-1057879Y-80844I-484J-124D01*
G02Y-76636I-797J2104D01*
G03X-1057217Y-76293I177J468D01*
G02X-1055993Y-73463I9541J-2447D01*
G03X-1056190Y-72749I-422J268D01*
G02X-1053106Y-69858I1014J2009D01*
G03X-1052406Y-70100I460J196D01*
G02X-1050123Y-69199I4730J-8640D01*
G03X-1049780Y-68538I-124J484D01*
G02X-1045572I2104J797D01*
G03X-1045229Y-69199I468J-177D01*
G02X-1042946Y-70100I-2447J-9541D01*
G03X-1042246Y-69858I240J439D01*
G02X-1039162Y-72749I2070J-882D01*
G03X-1039359Y-73463I225J-446D01*
G02X-1038135Y-76293I-8317J-5277D01*
G03X-1037473Y-76636I484J124D01*
G02Y-80844I797J-2104D01*
G03X-1038135Y-81187I-177J-468D01*
G02X-1039036Y-83470I-9541J2447D01*
G03X-1038794Y-84170I439J-240D01*
G02X-1041685Y-87254I-882J-2070D01*
G03X-1042399Y-87057I-446J-225D01*
G02X-1045229Y-88281I-5277J8317D01*
G03X-1045572Y-88943I124J-484D01*
G02X-1049780I-2104J-797D01*
G37*
G36*
G01X-965882Y-86300D02*
X-967776D01*
X-967837Y-86460D01*
G02X-970824I-1494J574D01*
G01X-970886Y-86300D01*
X-974500D01*
Y-72550D01*
X-972778D01*
G02X-970780I999J-1250D01*
G01X-945200D01*
Y-86300D01*
X-956615D01*
X-956787Y-86385D01*
X-957024Y-86300D01*
X-965473D01*
X-965645Y-86385D01*
X-965882Y-86300D01*
G37*
G36*
G01X-1411378Y-134126D02*
Y-145669D01*
G02X-1434764I-11693J0D01*
G01Y-134126D01*
G02X-1411378I11693J12078D01*
G37*
G36*
G01X-1167283Y-80818D02*
Y-92362D01*
G02X-1190669I-11693J0D01*
G01Y-80818D01*
G02X-1167283I11693J12078D01*
G37*
G36*
G01X-549173Y-104441D02*
Y-115984D01*
G02X-572559I-11693J0D01*
G01Y-104441D01*
G02X-549173I11693J12078D01*
G37*
G36*
G01X-490095Y-158465D02*
G03X-490143Y-157514I-177J468D01*
G02X-483477I3333J12514D01*
G03X-483525Y-158465I129J-483D01*
G02X-490095I-3285J-8701D01*
G37*
G36*
G01X-1347998Y-169894D02*
G02X-1360173Y-158465I-8891J2729D01*
G03X-1360221Y-157514I-177J468D01*
G02X-1353556I3333J12514D01*
G03X-1353604Y-158465I129J-483D01*
G02X-1347998Y-164437I-3285J-8701D01*
G02Y-169894I-8891J-2729D01*
G37*
G36*
G01X-1194760Y-176769D02*
G03X-1194930Y-177499I237J-440D01*
G02X-1199086I-2078J-1478D01*
G03X-1199260Y-176767I-407J290D01*
G01Y-174661D01*
G02Y-172268I2252J1197D01*
G01Y-169150D01*
G02Y-166756I2252J1197D01*
G01Y-164651D01*
G03X-1199086Y-163919I-234J442D01*
G02X-1199086Y-160963I2078J1478D01*
G03X-1199260Y-160231I-407J290D01*
G01Y-158126D01*
G02Y-155732I2252J1197D01*
G01Y-152614D01*
G02Y-150221I2252J1197D01*
G01Y-148115D01*
G03X-1199086Y-147383I-234J442D01*
G02Y-144428I2078J1478D01*
G03X-1199260Y-143696I-407J290D01*
G01Y-141590D01*
G02Y-139197I2252J1197D01*
G01Y-136079D01*
G02Y-133685I2252J1197D01*
G01Y-131580D01*
G03X-1199086Y-130848I-234J442D01*
G02X-1194930I2078J1478D01*
G03X-1194760Y-131578I407J-290D01*
G01Y-133679D01*
G02Y-136085I-2248J-1203D01*
G01Y-139190D01*
G02Y-141597I-2248J-1203D01*
G01Y-143698D01*
G03X-1194930Y-144428I237J-440D01*
G02Y-147383I-2078J-1478D01*
G03X-1194760Y-148113I407J-290D01*
G01Y-150214D01*
G02Y-152621I-2248J-1203D01*
G01Y-155726D01*
G02Y-158132I-2248J-1203D01*
G01Y-160233D01*
G03X-1194930Y-160963I237J-440D01*
G02X-1194930Y-163919I-2078J-1478D01*
G03X-1194760Y-164649I407J-290D01*
G01Y-166750D01*
G02Y-169156I-2248J-1203D01*
G01Y-172261D01*
G02Y-174668I-2248J-1203D01*
G01Y-176769D01*
G37*
G36*
G01X-1155390Y-179786D02*
Y-181827D01*
X-1159890D01*
Y-179779D01*
G02Y-177386I2252J1197D01*
G01Y-174268D01*
G02Y-171874I2252J1197D01*
G01Y-169769D01*
G03X-1159716Y-169037I-234J442D01*
G02X-1159716Y-166081I2078J1478D01*
G03X-1159890Y-165349I-407J290D01*
G01Y-163244D01*
G02Y-160850I2252J1197D01*
G01Y-157732D01*
G02Y-155339I2252J1197D01*
G01Y-153233D01*
G03X-1159716Y-152502I-234J442D01*
G02X-1159716Y-149546I2078J1478D01*
G03X-1159890Y-148814I-407J290D01*
G01Y-146709D01*
G02Y-144315I2252J1197D01*
G01Y-141197D01*
G02Y-138803I2252J1197D01*
G01Y-136698D01*
G03X-1159716Y-135966I-234J442D01*
G02X-1155560I2078J1478D01*
G03X-1155390Y-136696I407J-290D01*
G01Y-138797D01*
G02Y-141203I-2248J-1203D01*
G01Y-144309D01*
G02Y-146715I-2248J-1203D01*
G01Y-148816D01*
G03X-1155560Y-149546I237J-440D01*
G02X-1155560Y-152502I-2078J-1478D01*
G03X-1155390Y-153232I407J-290D01*
G01Y-155332D01*
G02Y-157739I-2248J-1203D01*
G01Y-160844D01*
G02Y-163250I-2248J-1203D01*
G01Y-165351D01*
G03X-1155560Y-166081I237J-440D01*
G02X-1155560Y-169037I-2078J-1478D01*
G03X-1155390Y-169767I407J-290D01*
G01Y-171868D01*
G02Y-174274I-2248J-1203D01*
G01Y-177379D01*
G02Y-179786I-2248J-1203D01*
G37*
G36*
G01X-1186886D02*
Y-181827D01*
X-1191386D01*
Y-179779D01*
G02Y-177386I2252J1197D01*
G01Y-174268D01*
G02Y-171874I2252J1197D01*
G01Y-169769D01*
G03X-1191212Y-169037I-234J442D01*
G02X-1187056I2078J1478D01*
G03X-1186886Y-169767I407J-290D01*
G01Y-171868D01*
G02Y-174274I-2248J-1203D01*
G01Y-177379D01*
G02Y-179786I-2248J-1203D01*
G37*
G36*
G01X-1188041Y-148720D02*
G02X-1190226I-1093J-2304D01*
G03Y-147816I-214J452D01*
G02Y-143208I1093J2304D01*
G03Y-142304I-214J452D01*
G02Y-137696I1093J2304D01*
G03Y-136792I-214J452D01*
G02X-1188041I1093J2304D01*
G03Y-137696I214J-452D01*
G02Y-142304I-1093J-2304D01*
G03Y-143208I214J-452D01*
G02Y-147816I-1093J-2304D01*
G03Y-148720I214J-452D01*
G37*
G36*
G01X-1163434Y-177499D02*
G02X-1167590I-2078J-1478D01*
G03X-1167764Y-176767I-407J290D01*
G01Y-174661D01*
G02Y-172268I2252J1197D01*
G01Y-169150D01*
G02Y-166756I2252J1197D01*
G01Y-164651D01*
G03X-1167590Y-163919I-234J442D01*
G02X-1166604Y-160137I2078J1478D01*
G03Y-159233I-214J452D01*
G02Y-154625I1093J2304D01*
G03Y-153721I-214J452D01*
G02Y-149113I1093J2304D01*
G03Y-148210I-214J452D01*
G02Y-143601I1093J2304D01*
G03Y-142698I-214J452D01*
G02Y-138090I1093J2304D01*
G03Y-137186I-214J452D01*
G02Y-132578I1093J2304D01*
G03Y-131674I-214J452D01*
G02X-1164419I1093J2304D01*
G03Y-132578I214J-452D01*
G02Y-137186I-1093J-2304D01*
G03Y-138090I214J-452D01*
G02Y-142698I-1093J-2304D01*
G03Y-143601I214J-452D01*
G02Y-148210I-1093J-2304D01*
G03Y-149113I214J-452D01*
G02Y-153721I-1093J-2304D01*
G03Y-154625I214J-452D01*
G02Y-159233I-1093J-2304D01*
G03Y-160137I214J-452D01*
G02X-1163434Y-163919I-1093J-2304D01*
G03X-1163264Y-164649I407J-290D01*
G01Y-166750D01*
G02Y-169156I-2248J-1203D01*
G01Y-172261D01*
G02Y-174668I-2248J-1203D01*
G01Y-176769D01*
G03X-1163434Y-177499I237J-440D01*
G37*
G36*
G01X-1179182D02*
G02X-1183338I-2078J-1478D01*
G03X-1183512Y-176767I-407J290D01*
G01Y-174661D01*
G02Y-172268I2252J1197D01*
G01Y-169150D01*
G02Y-166756I2252J1197D01*
G01Y-164651D01*
G03X-1183338Y-163919I-234J442D01*
G02X-1182352Y-160137I2078J1478D01*
G03Y-159233I-214J452D01*
G02Y-154625I1093J2304D01*
G03Y-153721I-214J452D01*
G02Y-149113I1093J2304D01*
G03Y-148210I-214J452D01*
G02Y-143601I1093J2304D01*
G03Y-142698I-214J452D01*
G02Y-138090I1093J2304D01*
G03Y-137186I-214J452D01*
G02Y-132578I1093J2304D01*
G03Y-131674I-214J452D01*
G02X-1180167I1093J2304D01*
G03Y-132578I214J-452D01*
G02Y-137186I-1093J-2304D01*
G03Y-138090I214J-452D01*
G02Y-142698I-1093J-2304D01*
G03Y-143601I214J-452D01*
G02Y-148210I-1093J-2304D01*
G03Y-149113I214J-452D01*
G02Y-153721I-1093J-2304D01*
G03Y-154625I214J-452D01*
G02Y-159233I-1093J-2304D01*
G03Y-160137I214J-452D01*
G02X-1179182Y-163919I-1093J-2304D01*
G03X-1179012Y-164649I407J-290D01*
G01Y-166750D01*
G02Y-169156I-2248J-1203D01*
G01Y-172261D01*
G02Y-174668I-2248J-1203D01*
G01Y-176769D01*
G03X-1179182Y-177499I237J-440D01*
G37*
G36*
G01X-1171138Y-181827D02*
X-1175638D01*
Y-179779D01*
G02Y-177386I2252J1197D01*
G01Y-174268D01*
G02Y-171874I2252J1197D01*
G01Y-169769D01*
G03X-1175464Y-169037I-234J442D01*
G02X-1174478Y-165255I2078J1478D01*
G03Y-164351I-214J452D01*
G02Y-159743I1093J2304D01*
G03Y-158840I-214J452D01*
G02Y-154231I1093J2304D01*
G03Y-153328I-214J452D01*
G02Y-148720I1093J2304D01*
G03Y-147816I-214J452D01*
G02Y-143208I1093J2304D01*
G03Y-142304I-214J452D01*
G02X-1172293I1093J2304D01*
G03Y-143208I214J-452D01*
G02Y-147816I-1093J-2304D01*
G03Y-148720I214J-452D01*
G02Y-153328I-1093J-2304D01*
G03Y-154231I214J-452D01*
G02Y-158840I-1093J-2304D01*
G03Y-159743I214J-452D01*
G02Y-164351I-1093J-2304D01*
G03Y-165255I214J-452D01*
G02X-1171308Y-169037I-1093J-2304D01*
G03X-1171138Y-169767I407J-290D01*
G01Y-171868D01*
G02Y-174274I-2248J-1203D01*
G01Y-177379D01*
G02Y-179786I-2248J-1203D01*
G01Y-181827D01*
G37*
G36*
G01X-285311Y-179786D02*
Y-181827D01*
X-289811D01*
Y-179779D01*
G02Y-177386I2252J1197D01*
G01Y-174268D01*
G02Y-171874I2252J1197D01*
G01Y-169769D01*
G03X-289637Y-169037I-234J442D01*
G02X-289637Y-166081I2078J1478D01*
G03X-289811Y-165349I-407J290D01*
G01Y-163244D01*
G02Y-160850I2252J1197D01*
G01Y-157732D01*
G02Y-155339I2252J1197D01*
G01Y-153233D01*
G03X-289637Y-152502I-234J442D01*
G02X-289637Y-149546I2078J1478D01*
G03X-289811Y-148814I-407J290D01*
G01Y-146709D01*
G02Y-144315I2252J1197D01*
G01Y-141197D01*
G02Y-138803I2252J1197D01*
G01Y-136698D01*
G03X-289637Y-135966I-234J442D01*
G02X-285481I2078J1478D01*
G03X-285311Y-136696I407J-290D01*
G01Y-138797D01*
G02Y-141203I-2248J-1203D01*
G01Y-144309D01*
G02Y-146715I-2248J-1203D01*
G01Y-148816D01*
G03X-285481Y-149546I237J-440D01*
G02X-285481Y-152502I-2078J-1478D01*
G03X-285311Y-153232I407J-290D01*
G01Y-155332D01*
G02Y-157739I-2248J-1203D01*
G01Y-160844D01*
G02Y-163250I-2248J-1203D01*
G01Y-165351D01*
G03X-285481Y-166081I237J-440D01*
G02X-285481Y-169037I-2078J-1478D01*
G03X-285311Y-169767I407J-290D01*
G01Y-171868D01*
G02Y-174274I-2248J-1203D01*
G01Y-177379D01*
G02Y-179786I-2248J-1203D01*
G37*
G36*
G01X-316807D02*
Y-181827D01*
X-321307D01*
Y-179779D01*
G02Y-177386I2252J1197D01*
G01Y-174268D01*
G02Y-171874I2252J1197D01*
G01Y-169769D01*
G03X-321133Y-169037I-234J442D01*
G02X-316977I2078J1478D01*
G03X-316807Y-169767I407J-290D01*
G01Y-171868D01*
G02Y-174274I-2248J-1203D01*
G01Y-177379D01*
G02Y-179786I-2248J-1203D01*
G37*
G36*
G01X-317963Y-148720D02*
G02X-320148I-1093J-2304D01*
G03Y-147816I-214J452D01*
G02Y-143208I1093J2304D01*
G03Y-142304I-214J452D01*
G02Y-137696I1093J2304D01*
G03Y-136792I-214J452D01*
G02X-317963I1093J2304D01*
G03Y-137696I214J-452D01*
G02Y-142304I-1093J-2304D01*
G03Y-143208I214J-452D01*
G02Y-147816I-1093J-2304D01*
G03Y-148720I214J-452D01*
G37*
G36*
G01X-276690Y-178957D02*
G02Y-177443I-1410J757D01*
G03X-275810I440J237D01*
G02Y-178957I1410J-757D01*
G03X-276690I-440J-237D01*
G37*
G36*
G01X-293355Y-177499D02*
G02X-297511I-2078J-1478D01*
G03X-297685Y-176767I-407J290D01*
G01Y-174661D01*
G02Y-172268I2252J1197D01*
G01Y-169150D01*
G02Y-166756I2252J1197D01*
G01Y-164651D01*
G03X-297511Y-163919I-234J442D01*
G02X-296526Y-160137I2078J1478D01*
G03Y-159233I-214J452D01*
G02Y-154625I1093J2304D01*
G03Y-153721I-214J452D01*
G02Y-149113I1093J2304D01*
G03Y-148210I-214J452D01*
G02Y-143601I1093J2304D01*
G03Y-142698I-214J452D01*
G02Y-138090I1093J2304D01*
G03Y-137186I-214J452D01*
G02Y-132578I1093J2304D01*
G03Y-131674I-214J452D01*
G02X-294341I1093J2304D01*
G03Y-132578I214J-452D01*
G02Y-137186I-1093J-2304D01*
G03Y-138090I214J-452D01*
G02Y-142698I-1093J-2304D01*
G03Y-143601I214J-452D01*
G02Y-148210I-1093J-2304D01*
G03Y-149113I214J-452D01*
G02Y-153721I-1093J-2304D01*
G03Y-154625I214J-452D01*
G02Y-159233I-1093J-2304D01*
G03Y-160137I214J-452D01*
G02X-293355Y-163919I-1093J-2304D01*
G03X-293185Y-164649I407J-290D01*
G01Y-166750D01*
G02Y-169156I-2248J-1203D01*
G01Y-172261D01*
G02Y-174668I-2248J-1203D01*
G01Y-176769D01*
G03X-293355Y-177499I237J-440D01*
G37*
G36*
G01X-309103D02*
G02X-313259I-2078J-1478D01*
G03X-313433Y-176767I-407J290D01*
G01Y-174661D01*
G02Y-172268I2252J1197D01*
G01Y-169150D01*
G02Y-166756I2252J1197D01*
G01Y-164651D01*
G03X-313259Y-163919I-234J442D01*
G02X-312274Y-160137I2078J1478D01*
G03Y-159233I-214J452D01*
G02Y-154625I1093J2304D01*
G03Y-153721I-214J452D01*
G02Y-149113I1093J2304D01*
G03Y-148210I-214J452D01*
G02Y-143601I1093J2304D01*
G03Y-142698I-214J452D01*
G02Y-138090I1093J2304D01*
G03Y-137186I-214J452D01*
G02Y-132578I1093J2304D01*
G03Y-131674I-214J452D01*
G02X-310089I1093J2304D01*
G03Y-132578I214J-452D01*
G02Y-137186I-1093J-2304D01*
G03Y-138090I214J-452D01*
G02Y-142698I-1093J-2304D01*
G03Y-143601I214J-452D01*
G02Y-148210I-1093J-2304D01*
G03Y-149113I214J-452D01*
G02Y-153721I-1093J-2304D01*
G03Y-154625I214J-452D01*
G02Y-159233I-1093J-2304D01*
G03Y-160137I214J-452D01*
G02X-309103Y-163919I-1093J-2304D01*
G03X-308933Y-164649I407J-290D01*
G01Y-166750D01*
G02Y-169156I-2248J-1203D01*
G01Y-172261D01*
G02Y-174668I-2248J-1203D01*
G01Y-176769D01*
G03X-309103Y-177499I237J-440D01*
G37*
G36*
G01X-301059Y-181827D02*
X-305559D01*
Y-179779D01*
G02Y-177386I2252J1197D01*
G01Y-174268D01*
G02Y-171874I2252J1197D01*
G01Y-169769D01*
G03X-305385Y-169037I-234J442D01*
G02X-304400Y-165255I2078J1478D01*
G03Y-164351I-214J452D01*
G02Y-159743I1093J2304D01*
G03Y-158840I-214J452D01*
G02Y-154231I1093J2304D01*
G03Y-153328I-214J452D01*
G02Y-148720I1093J2304D01*
G03Y-147816I-214J452D01*
G02Y-143208I1093J2304D01*
G03Y-142304I-214J452D01*
G02X-302215I1093J2304D01*
G03Y-143208I214J-452D01*
G02Y-147816I-1093J-2304D01*
G03Y-148720I214J-452D01*
G02Y-153328I-1093J-2304D01*
G03Y-154231I214J-452D01*
G02Y-158840I-1093J-2304D01*
G03Y-159743I214J-452D01*
G02Y-164351I-1093J-2304D01*
G03Y-165255I214J-452D01*
G02X-301229Y-169037I-1093J-2304D01*
G03X-301059Y-169767I407J-290D01*
G01Y-171868D01*
G02Y-174274I-2248J-1203D01*
G01Y-177379D01*
G02Y-179786I-2248J-1203D01*
G01Y-181827D01*
G37*
G36*
G01X-119695Y-176279D02*
G02X-121880I-1093J-2304D01*
G03Y-175375I-214J452D01*
G02X-119695I1093J2304D01*
G03Y-176279I214J-452D01*
G37*
G36*
G01X-127569Y-171160D02*
G02X-129754I-1093J-2304D01*
G03Y-170257I-214J452D01*
G02X-127569I1093J2304D01*
G03Y-171160I214J-452D01*
G37*
G36*
G01X-134285Y-179783D02*
Y-181827D01*
X-138785D01*
Y-179783D01*
G02Y-177383I2250J1200D01*
G01Y-174271D01*
G02Y-171871I2250J1200D01*
G01Y-169827D01*
X-134285D01*
Y-171871D01*
G02Y-174271I-2250J-1200D01*
G01Y-177383D01*
G02Y-179783I-2250J-1200D01*
G37*
G36*
G01X-102789D02*
Y-181827D01*
X-107289D01*
Y-179783D01*
G02Y-177383I2250J1200D01*
G01Y-174271D01*
G02Y-171871I2250J1200D01*
G01Y-169827D01*
X-102789D01*
Y-171871D01*
G02Y-174271I-2250J-1200D01*
G01Y-177383D01*
G02Y-179783I-2250J-1200D01*
G37*
G36*
G01X-142159Y-174665D02*
Y-176709D01*
X-146659D01*
Y-174665D01*
G02Y-172265I2250J1200D01*
G01Y-169153D01*
G02Y-166753I2250J1200D01*
G01Y-164709D01*
X-142159D01*
Y-166753D01*
G02Y-169153I-2250J-1200D01*
G01Y-172265D01*
G02Y-174665I-2250J-1200D01*
G37*
G36*
G01X-110663D02*
Y-176709D01*
X-115163D01*
Y-174665D01*
G02Y-172265I2250J1200D01*
G01Y-169153D01*
G02Y-166753I2250J1200D01*
G01Y-164709D01*
X-110663D01*
Y-166753D01*
G02Y-169153I-2250J-1200D01*
G01Y-172265D01*
G02Y-174665I-2250J-1200D01*
G37*
G36*
G01X-134285Y-163247D02*
Y-165291D01*
X-138785D01*
Y-163247D01*
G02Y-160847I2250J1200D01*
G01Y-157735D01*
G02Y-155335I2250J1200D01*
G01Y-153291D01*
X-134285D01*
Y-155335D01*
G02Y-157735I-2250J-1200D01*
G01Y-160847D01*
G02Y-163247I-2250J-1200D01*
G37*
G36*
G01X-118537D02*
Y-165291D01*
X-123037D01*
Y-163247D01*
G02Y-160847I2250J1200D01*
G01Y-157735D01*
G02Y-155335I2250J1200D01*
G01Y-153291D01*
X-118537D01*
Y-155335D01*
G02Y-157735I-2250J-1200D01*
G01Y-160847D01*
G02Y-163247I-2250J-1200D01*
G37*
G36*
G01X-102789D02*
Y-165291D01*
X-107289D01*
Y-163247D01*
G02Y-160847I2250J1200D01*
G01Y-157735D01*
G02Y-155335I2250J1200D01*
G01Y-153291D01*
X-102789D01*
Y-155335D01*
G02Y-157735I-2250J-1200D01*
G01Y-160847D01*
G02Y-163247I-2250J-1200D01*
G37*
G36*
G01X-142159Y-158129D02*
Y-160173D01*
X-146659D01*
Y-158129D01*
G02Y-155729I2250J1200D01*
G01Y-152617D01*
G02Y-150217I2250J1200D01*
G01Y-148173D01*
X-142159D01*
Y-150217D01*
G02Y-152617I-2250J-1200D01*
G01Y-155729D01*
G02Y-158129I-2250J-1200D01*
G37*
G36*
G01X-126411D02*
Y-160173D01*
X-130911D01*
Y-158129D01*
G02Y-155729I2250J1200D01*
G01Y-152617D01*
G02Y-150217I2250J1200D01*
G01Y-148173D01*
X-126411D01*
Y-150217D01*
G02Y-152617I-2250J-1200D01*
G01Y-155729D01*
G02Y-158129I-2250J-1200D01*
G37*
G36*
G01X-110663D02*
Y-160173D01*
X-115163D01*
Y-158129D01*
G02Y-155729I2250J1200D01*
G01Y-152617D01*
G02Y-150217I2250J1200D01*
G01Y-148173D01*
X-110663D01*
Y-150217D01*
G02Y-152617I-2250J-1200D01*
G01Y-155729D01*
G02Y-158129I-2250J-1200D01*
G37*
G36*
G01X-134285Y-146712D02*
Y-148756D01*
X-138785D01*
Y-146712D01*
G02Y-144312I2250J1200D01*
G01Y-141200D01*
G02Y-138800I2250J1200D01*
G01Y-136756D01*
X-134285D01*
Y-138800D01*
G02Y-141200I-2250J-1200D01*
G01Y-144312D01*
G02Y-146712I-2250J-1200D01*
G37*
G36*
G01X-118537D02*
Y-148756D01*
X-123037D01*
Y-146712D01*
G02Y-144312I2250J1200D01*
G01Y-141200D01*
G02Y-138800I2250J1200D01*
G01Y-136756D01*
X-118537D01*
Y-138800D01*
G02Y-141200I-2250J-1200D01*
G01Y-144312D01*
G02Y-146712I-2250J-1200D01*
G37*
G36*
G01X-102789D02*
Y-148756D01*
X-107289D01*
Y-146712D01*
G02Y-144312I2250J1200D01*
G01Y-141200D01*
G02Y-138800I2250J1200D01*
G01Y-136756D01*
X-102789D01*
Y-138800D01*
G02Y-141200I-2250J-1200D01*
G01Y-144312D01*
G02Y-146712I-2250J-1200D01*
G37*
G36*
G01X-142159Y-141594D02*
Y-143638D01*
X-146659D01*
Y-141594D01*
G02Y-139194I2250J1200D01*
G01Y-136082D01*
G02Y-133682I2250J1200D01*
G01Y-131638D01*
X-142159D01*
Y-133682D01*
G02Y-136082I-2250J-1200D01*
G01Y-139194D01*
G02Y-141594I-2250J-1200D01*
G37*
G36*
G01X-126411D02*
Y-143638D01*
X-130911D01*
Y-141594D01*
G02Y-139194I2250J1200D01*
G01Y-136082D01*
G02Y-133682I2250J1200D01*
G01Y-131638D01*
X-126411D01*
Y-133682D01*
G02Y-136082I-2250J-1200D01*
G01Y-139194D01*
G02Y-141594I-2250J-1200D01*
G37*
G36*
G01X-110663D02*
Y-143638D01*
X-115163D01*
Y-141594D01*
G02Y-139194I2250J1200D01*
G01Y-136082D01*
G02Y-133682I2250J1200D01*
G01Y-131638D01*
X-110663D01*
Y-133682D01*
G02Y-136082I-2250J-1200D01*
G01Y-139194D01*
G02Y-141594I-2250J-1200D01*
G37*
G36*
G01X-138939Y-94669D02*
X-142507Y-96333D01*
X-143491Y-95924D01*
X-144655Y-93427D01*
X-143765Y-90840D01*
X-142338Y-90174D01*
X-139784Y-91155D01*
X-138619Y-93653D01*
X-138939Y-94669D01*
G37*
G36*
G01Y-79708D02*
X-142507Y-81372D01*
X-143491Y-80964D01*
X-144655Y-78466D01*
X-143765Y-75879D01*
X-142338Y-75214D01*
X-139784Y-76194D01*
X-138619Y-78692D01*
X-138939Y-79708D01*
G37*
G36*
G01Y-64748D02*
X-142507Y-66412D01*
X-143491Y-66003D01*
X-144655Y-63505D01*
X-143765Y-60919D01*
X-142338Y-60253D01*
X-139784Y-61234D01*
X-138619Y-63732D01*
X-138939Y-64748D01*
G37*
G36*
G01Y-49787D02*
X-142507Y-51451D01*
X-143491Y-51043D01*
X-144655Y-48545D01*
X-143765Y-45958D01*
X-142338Y-45293D01*
X-139784Y-46273D01*
X-138619Y-48771D01*
X-138939Y-49787D01*
G37*
G36*
G01X-130080Y-94669D02*
X-133649Y-96333D01*
X-134632Y-95924D01*
X-135797Y-93427D01*
X-134907Y-90840D01*
X-133479Y-90174D01*
X-130926Y-91155D01*
X-129761Y-93653D01*
X-130080Y-94669D01*
G37*
G36*
G01X-142373Y-67007D02*
X-138843Y-65263D01*
X-137850Y-65650D01*
X-136630Y-68121D01*
X-137461Y-70727D01*
X-138874Y-71424D01*
X-141449Y-70501D01*
X-142669Y-68030D01*
X-142373Y-67007D01*
G37*
G36*
G01Y-81968D02*
X-138843Y-80224D01*
X-137850Y-80610D01*
X-136630Y-83081D01*
X-137461Y-85687D01*
X-138874Y-86385D01*
X-141449Y-85462D01*
X-142669Y-82991D01*
X-142373Y-81968D01*
G37*
G36*
G01X-130080Y-79708D02*
X-133649Y-81372D01*
X-134632Y-80964D01*
X-135797Y-78466D01*
X-134907Y-75879D01*
X-133479Y-75214D01*
X-130926Y-76194D01*
X-129761Y-78692D01*
X-130080Y-79708D01*
G37*
G36*
G01X-133515Y-81968D02*
X-129985Y-80224D01*
X-128992Y-80610D01*
X-127771Y-83081D01*
X-128603Y-85687D01*
X-130015Y-86385D01*
X-132590Y-85462D01*
X-133811Y-82991D01*
X-133515Y-81968D01*
G37*
G36*
G01Y-67007D02*
X-129985Y-65263D01*
X-128992Y-65650D01*
X-127771Y-68121D01*
X-128603Y-70727D01*
X-130015Y-71424D01*
X-132590Y-70501D01*
X-133811Y-68030D01*
X-133515Y-67007D01*
G37*
G36*
G01X-142373Y-52047D02*
X-138843Y-50303D01*
X-137850Y-50689D01*
X-136630Y-53160D01*
X-137461Y-55766D01*
X-138874Y-56464D01*
X-141449Y-55541D01*
X-142669Y-53070D01*
X-142373Y-52047D01*
G37*
G36*
G01X-130080Y-64748D02*
X-133649Y-66412D01*
X-134632Y-66003D01*
X-135797Y-63505D01*
X-134907Y-60919D01*
X-133479Y-60253D01*
X-130926Y-61234D01*
X-129761Y-63732D01*
X-130080Y-64748D01*
G37*
G36*
G01X-133515Y-52047D02*
X-129985Y-50303D01*
X-128992Y-50689D01*
X-127771Y-53160D01*
X-128603Y-55766D01*
X-130015Y-56464D01*
X-132590Y-55541D01*
X-133811Y-53070D01*
X-133515Y-52047D01*
G37*
G36*
G01X-95632Y-94669D02*
X-99200Y-96333D01*
X-100184Y-95924D01*
X-101348Y-93427D01*
X-100458Y-90840D01*
X-99031Y-90174D01*
X-96477Y-91155D01*
X-95312Y-93653D01*
X-95632Y-94669D01*
G37*
G36*
G01Y-79708D02*
X-99200Y-81372D01*
X-100184Y-80964D01*
X-101348Y-78466D01*
X-100458Y-75879D01*
X-99031Y-75214D01*
X-96477Y-76194D01*
X-95312Y-78692D01*
X-95632Y-79708D01*
G37*
G36*
G01X-99066Y-81968D02*
X-95536Y-80224D01*
X-94543Y-80610D01*
X-93323Y-83081D01*
X-94154Y-85687D01*
X-95566Y-86385D01*
X-98142Y-85462D01*
X-99362Y-82991D01*
X-99066Y-81968D01*
G37*
G36*
G01Y-67007D02*
X-95536Y-65263D01*
X-94543Y-65650D01*
X-93323Y-68121D01*
X-94154Y-70727D01*
X-95566Y-71424D01*
X-98142Y-70501D01*
X-99362Y-68030D01*
X-99066Y-67007D01*
G37*
G36*
G01X-95632Y-64748D02*
X-99200Y-66412D01*
X-100184Y-66003D01*
X-101348Y-63505D01*
X-100458Y-60919D01*
X-99031Y-60253D01*
X-96477Y-61234D01*
X-95312Y-63732D01*
X-95632Y-64748D01*
G37*
G36*
G01X-99066Y-52047D02*
X-95536Y-50303D01*
X-94543Y-50689D01*
X-93323Y-53160D01*
X-94154Y-55766D01*
X-95566Y-56464D01*
X-98142Y-55541D01*
X-99362Y-53070D01*
X-99066Y-52047D01*
G37*
G36*
G01X-95632Y-49787D02*
X-99200Y-51451D01*
X-100184Y-51043D01*
X-101348Y-48545D01*
X-100458Y-45958D01*
X-99031Y-45293D01*
X-96477Y-46273D01*
X-95312Y-48771D01*
X-95632Y-49787D01*
G37*
G36*
G01X-86773Y-94669D02*
X-90342Y-96333D01*
X-91325Y-95924D01*
X-92490Y-93427D01*
X-91600Y-90840D01*
X-90172Y-90174D01*
X-87619Y-91155D01*
X-86454Y-93653D01*
X-86773Y-94669D01*
G37*
G36*
G01X-90207Y-67007D02*
X-86678Y-65263D01*
X-85685Y-65650D01*
X-84464Y-68121D01*
X-85296Y-70727D01*
X-86708Y-71424D01*
X-89283Y-70501D01*
X-90504Y-68030D01*
X-90207Y-67007D01*
G37*
G36*
G01Y-81968D02*
X-86678Y-80224D01*
X-85685Y-80610D01*
X-84464Y-83081D01*
X-85296Y-85687D01*
X-86708Y-86385D01*
X-89283Y-85462D01*
X-90504Y-82991D01*
X-90207Y-81968D01*
G37*
G36*
G01X-86773Y-79708D02*
X-90342Y-81372D01*
X-91325Y-80964D01*
X-92490Y-78466D01*
X-91600Y-75879D01*
X-90172Y-75214D01*
X-87619Y-76194D01*
X-86454Y-78692D01*
X-86773Y-79708D01*
G37*
G36*
G01X-90207Y-52047D02*
X-86678Y-50303D01*
X-85685Y-50689D01*
X-84464Y-53160D01*
X-85296Y-55766D01*
X-86708Y-56464D01*
X-89283Y-55541D01*
X-90504Y-53070D01*
X-90207Y-52047D01*
G37*
G36*
G01X-86773Y-64748D02*
X-90342Y-66412D01*
X-91325Y-66003D01*
X-92490Y-63505D01*
X-91600Y-60919D01*
X-90172Y-60253D01*
X-87619Y-61234D01*
X-86454Y-63732D01*
X-86773Y-64748D01*
G37*
G36*
G01X-134463Y-44741D02*
G02X-127197Y-30498I1195J8365D01*
G02X-127315Y-42373I-6071J-5877D01*
G02X-132239Y-44763I-5953J5997D01*
G03X-132353Y-45725I65J-496D01*
G01X-130926Y-46273D01*
X-129761Y-48771D01*
X-130080Y-49787D01*
X-133649Y-51451D01*
X-134632Y-51043D01*
X-135797Y-48545D01*
X-134907Y-45958D01*
X-134327Y-45688D01*
G03X-134463Y-44741I-211J453D01*
G37*
G36*
G01X-91156D02*
G02X-83889Y-30498I1195J8365D01*
G02X-84008Y-42373I-6071J-5877D01*
G02X-88932Y-44763I-5953J5997D01*
G03X-89046Y-45725I65J-496D01*
G01X-87619Y-46273D01*
X-86454Y-48771D01*
X-86773Y-49787D01*
X-90342Y-51451D01*
X-91325Y-51043D01*
X-92490Y-48545D01*
X-91600Y-45958D01*
X-91020Y-45688D01*
G03X-91156Y-44741I-211J453D01*
G37*
G36*
G01X-142669Y-97952D02*
X-142373Y-96928D01*
X-138843Y-95185D01*
X-137850Y-95571D01*
X-136630Y-98042D01*
X-137461Y-100648D01*
X-138874Y-101346D01*
X-141449Y-100423D01*
X-142669Y-97952D01*
G37*
G36*
G01X-133811D02*
X-133515Y-96928D01*
X-129985Y-95185D01*
X-128992Y-95571D01*
X-127771Y-98042D01*
X-128603Y-100648D01*
X-130015Y-101346D01*
X-132590Y-100423D01*
X-133811Y-97952D01*
G37*
G36*
G01X-99362D02*
X-99066Y-96928D01*
X-95536Y-95185D01*
X-94543Y-95571D01*
X-93323Y-98042D01*
X-94154Y-100648D01*
X-95566Y-101346D01*
X-98142Y-100423D01*
X-99362Y-97952D01*
G37*
G36*
G01X-90504D02*
X-90207Y-96928D01*
X-86678Y-95185D01*
X-85685Y-95571D01*
X-84464Y-98042D01*
X-85296Y-100648D01*
X-86708Y-101346D01*
X-89283Y-100423D01*
X-90504Y-97952D01*
G37*
G54D28*
X-352500Y12500D03*
X-348000Y-19000D03*
X-361500D03*
Y-31500D03*
X-348000D03*
Y-44000D03*
X-361500D03*
X-348000Y-57000D03*
X-361500Y-56500D03*
X-377500Y12500D03*
X-365000D03*
X-374000Y-19000D03*
Y-31500D03*
Y-44000D03*
Y-56500D03*
X-390000Y12500D03*
X-386500Y-5500D03*
Y-19000D03*
Y-31500D03*
Y-44000D03*
Y-56500D03*
X-402500Y12500D03*
X-413500D03*
X-424600Y-14400D03*
X-427500Y12500D03*
X-441959Y-35600D03*
X-442000Y-29480D03*
X-430400Y-35600D03*
X-441959Y-52100D03*
Y-41100D03*
X-429400D03*
X-430180Y-52100D03*
X-441959Y-57600D03*
Y-63100D03*
X-430700D03*
X-429000Y-57600D03*
X-441959Y-68600D03*
X-429900Y-79600D03*
X-441959Y-74100D03*
X-436771Y-92400D03*
X-432118Y-87082D03*
X-452500Y12500D03*
X-448600Y-5900D03*
X-443941Y6559D03*
X-454421Y-26959D03*
X-442800Y-46600D03*
X-449100Y-60841D03*
X-452700Y-69000D03*
X-444440Y-80710D03*
X-456240Y-82020D03*
X-461441Y6559D03*
X-465000Y-25000D03*
X-477500Y12500D03*
Y-37500D03*
X-486421Y-26159D03*
X-502500Y12500D03*
X-490000Y0D03*
X-502500Y-12500D03*
Y-37500D03*
Y-77500D03*
X-490000Y-90000D03*
X-502500Y-102500D03*
X-515000Y0D03*
Y-25000D03*
Y-65000D03*
Y-90000D03*
Y-115000D03*
Y-140000D03*
Y-165000D03*
X-527500Y12500D03*
Y-12500D03*
Y-37500D03*
Y-77500D03*
Y-102500D03*
Y-127500D03*
Y-152500D03*
Y-177500D03*
X-552500Y12500D03*
X-540000Y0D03*
X-552500Y-12500D03*
Y-37500D03*
X-540000Y-25000D03*
Y-65000D03*
Y-90000D03*
Y-115000D03*
Y-140000D03*
X-552500Y-152500D03*
Y-177500D03*
X-540000Y-165000D03*
X-565000Y0D03*
Y-25000D03*
Y-65000D03*
Y-140000D03*
Y-165000D03*
X-577500Y12500D03*
Y-12500D03*
Y-37500D03*
Y-127500D03*
Y-152500D03*
Y-177500D03*
X-590000Y0D03*
Y-25000D03*
X-602500Y12500D03*
Y-12500D03*
Y-37500D03*
X-616000Y14500D03*
Y-12500D03*
X-630000D03*
Y-25500D03*
X-616000Y-37500D03*
X-632500Y14500D03*
X-660000D03*
X-655500Y-500D03*
Y-12500D03*
Y-37500D03*
X-672500Y5000D03*
Y-20000D03*
Y-45000D03*
X-685000Y14500D03*
Y-7500D03*
X-710000Y14500D03*
X-697500Y5000D03*
X-710000Y-7500D03*
X-697500Y-20000D03*
Y-45000D03*
X-722500Y5000D03*
Y-20000D03*
Y-45000D03*
X-735000Y14500D03*
Y-7500D03*
Y-57500D03*
X-747500Y5000D03*
Y-20000D03*
Y-45000D03*
X-760000Y14500D03*
X-772500Y5000D03*
Y-20000D03*
X-760000Y-7500D03*
X-772500Y-45000D03*
X-760000Y-57500D03*
X-772500Y-70000D03*
X-760000Y-82500D03*
X-772500Y-95000D03*
X-760000Y-107500D03*
X-772500Y-120000D03*
X-760000Y-132500D03*
X-772500Y-145000D03*
Y-170000D03*
X-785000Y14500D03*
Y-7500D03*
Y-45000D03*
Y-57500D03*
Y-70000D03*
X-785500Y-120000D03*
X-797500Y5000D03*
Y-20000D03*
Y-45000D03*
Y-57500D03*
Y-70000D03*
Y-120000D03*
X-810000Y14500D03*
Y-7500D03*
Y-45000D03*
Y-57500D03*
Y-70000D03*
Y-120000D03*
Y-132500D03*
Y-145000D03*
Y-157500D03*
Y-170000D03*
X-835500Y14500D03*
X-822500Y5000D03*
Y-20000D03*
Y-45000D03*
X-835000Y-57500D03*
X-822500Y-70000D03*
X-835000Y-82500D03*
X-822500Y-95000D03*
X-835000Y-107500D03*
X-822500Y-120000D03*
X-835000Y-132500D03*
X-822500Y-145000D03*
X-835000Y-159500D03*
X-822500Y-170000D03*
X-847500Y5000D03*
Y-20000D03*
Y-45000D03*
Y-70000D03*
Y-95000D03*
Y-170000D03*
X-860000Y14500D03*
Y-7500D03*
Y-57500D03*
Y-82500D03*
Y-107500D03*
Y-132500D03*
Y-159500D03*
X-872500Y5000D03*
Y-20000D03*
Y-45000D03*
Y-70000D03*
Y-95000D03*
Y-170000D03*
X-885000Y14500D03*
X-897500Y5000D03*
Y-20000D03*
X-885000Y-7500D03*
X-897500Y-45000D03*
X-885000Y-57500D03*
X-897500Y-70000D03*
X-885000Y-82500D03*
X-897500Y-95000D03*
X-885000Y-107500D03*
Y-132500D03*
Y-159500D03*
X-897500Y-170000D03*
X-909500Y14500D03*
X-910000Y-7500D03*
Y-57500D03*
Y-82500D03*
Y-107500D03*
Y-132500D03*
Y-159500D03*
X-922500Y5000D03*
Y-20000D03*
Y-45000D03*
Y-70000D03*
Y-95000D03*
Y-120000D03*
Y-170000D03*
X-932500Y14500D03*
Y-7500D03*
X-957500Y14500D03*
Y-7500D03*
X-982500Y14500D03*
X-983000Y-7500D03*
X-1007500Y14500D03*
X-1012500Y-7500D03*
X-1012860Y-41250D03*
X-1022140Y-122960D03*
X-1017670Y-123250D03*
X-1032500Y14500D03*
X-1033843Y-128576D03*
X-1047300Y-2700D03*
X-1050811Y2600D03*
X-1054600Y-5100D03*
X-1041300Y-16500D03*
Y-10100D03*
X-1047289Y-26300D03*
X-1051400Y-26000D03*
X-1045400Y-38000D03*
X-1054900Y-29800D03*
X-1051200Y-44100D03*
X-1044300Y-47661D03*
X-1045100Y-52900D03*
X-1061900Y-5200D03*
X-1062000Y-29200D03*
X-1063600Y-56600D03*
X-1056900Y-56300D03*
X-1073000Y-90300D03*
X-1095000Y14500D03*
X-1100000Y-15000D03*
X-1093400Y-90200D03*
X-1099400D03*
X-1099010Y-104183D03*
X-1102953Y-104200D03*
X-1111500Y-2500D03*
X-1107800Y-68200D03*
X-1107700Y-63100D03*
Y-73400D03*
X-1106102Y-102100D03*
X-1109300Y-104200D03*
X-1112402Y-101600D03*
X-1118701Y-101759D03*
X-1115490Y-104240D03*
X-1120000Y14500D03*
X-1126000Y-15000D03*
X-1128810Y-104171D03*
X-1121870Y-104330D03*
X-1125000Y-101700D03*
X-1145000Y14500D03*
X-1137500Y-2500D03*
X-1159700Y-5750D03*
X-1158700Y-16250D03*
X-1159800Y-33100D03*
X-1160150Y-26750D03*
X-1159700Y-43900D03*
X-1160000Y-38500D03*
X-1154400Y-107900D03*
X-1154200Y-103100D03*
X-1160000Y-115100D03*
X-1170000Y14500D03*
X-1172100Y-5400D03*
X-1178800Y-5800D03*
X-1171800Y-16250D03*
X-1171500Y-21750D03*
X-1172000Y-10750D03*
X-1177800Y-12100D03*
X-1178800Y-34800D03*
X-1171800Y-26950D03*
X-1178950Y-23250D03*
X-1172500Y-38500D03*
X-1179000Y-40500D03*
X-1178900Y-46700D03*
X-1173200Y-49700D03*
X-1172500Y-44000D03*
X-1170300Y-114600D03*
X-1176100Y-114800D03*
X-1195000Y14500D03*
X-1191500Y0D03*
X-1192359Y-5800D03*
X-1191200Y-12128D03*
X-1191000Y-18250D03*
X-1190800Y-23450D03*
X-1191900Y-29500D03*
X-1191500Y-34000D03*
X-1191000Y-46500D03*
X-1191200Y-40500D03*
X-1199500Y5400D03*
X-1202100Y-103200D03*
X-1220000Y14500D03*
X-1245000D03*
Y-20000D03*
Y-45000D03*
X-1232500D03*
Y-57500D03*
X-1245000Y-70000D03*
X-1236310Y-140390D03*
X-1257500Y-57500D03*
X-1250660Y-140480D03*
X-1270000Y14500D03*
X-1295000D03*
X-1307500Y7000D03*
X-1295400Y-13400D03*
X-1298800Y-30200D03*
X-1298700Y-35700D03*
X-1298000Y-41200D03*
X-1298780Y-52200D03*
X-1298400Y-63200D03*
X-1297995Y-58405D03*
X-1302400Y-84100D03*
X-1300350Y-88500D03*
X-1306850Y-95000D03*
X-1320000Y14500D03*
X-1318500Y-6000D03*
X-1320000Y-500D03*
X-1310559Y-35700D03*
X-1311200Y-30200D03*
X-1310559Y-52200D03*
Y-41200D03*
X-1310600Y-46690D03*
X-1310559Y-57700D03*
Y-63200D03*
Y-68700D03*
X-1317700Y-60200D03*
X-1310559Y-74200D03*
X-1317700Y-72700D03*
X-1313040Y-80810D03*
X-1321000Y-94850D03*
X-1332500Y7000D03*
Y-27500D03*
X-1324500Y-26959D03*
X-1337500Y-62500D03*
X-1324840Y-82120D03*
X-1330400Y-74900D03*
X-1345000Y14500D03*
Y-500D03*
X-1343200Y-82700D03*
X-1350600Y-75000D03*
X-1370000Y14500D03*
X-1357500Y7000D03*
X-1370000Y-500D03*
X-1357500Y-8000D03*
X-1356700Y-25600D03*
X-1362500Y-62500D03*
X-1368750Y-82500D03*
X-1356250D03*
X-1363750Y-106250D03*
X-1382500Y7000D03*
Y-8000D03*
X-1373800Y-52900D03*
X-1375000Y-75000D03*
X-1381250Y-82500D03*
X-1380000Y-106250D03*
X-1371250Y-112500D03*
X-1395518Y14053D03*
X-1395000Y-500D03*
X-1394500Y-18000D03*
X-1387500Y-62500D03*
X-1400000Y-75000D03*
X-1393750Y-82500D03*
X-1400500Y-96500D03*
X-1400000Y-112500D03*
X-1395000Y-106250D03*
X-1400100Y-131550D03*
X-1387500Y-125000D03*
X-1387300Y-133200D03*
X-1400000Y-162500D03*
X-1387500Y-150000D03*
Y-175000D03*
X-1412500Y-62500D03*
X-1406250Y-82500D03*
X-1418500Y-93500D03*
X-1412000Y-100500D03*
X-1406250Y-106250D03*
X-1412500Y-175000D03*
X-1420000Y14500D03*
X-1419500Y-18000D03*
X-1431500Y-81000D03*
X-1421250Y-81250D03*
X-1430000Y-75400D03*
X-1430500Y-93500D03*
X-1425000Y-162500D03*
X-1435000Y1000D03*
X-1448900Y-76100D03*
X-1450000Y-87500D03*
X-1436500D03*
X-1437500Y-100000D03*
X-1450000Y-137500D03*
Y-162500D03*
X-1437500Y-175000D03*
X-1465063Y-22160D03*
Y-17160D03*
Y-12160D03*
X-1450000Y-112500D03*
X-1480063Y-22160D03*
X-1475063Y-17160D03*
Y-12160D03*
X-1480063Y-17160D03*
Y-12160D03*
X-1470063Y-22160D03*
Y-17160D03*
Y-12160D03*
X-1475063Y-22160D03*
X-1490063D03*
X-1495063D03*
X-1490063Y-17160D03*
Y-12160D03*
X-1495063Y-17160D03*
Y-12160D03*
X-1485063Y-22160D03*
Y-17160D03*
Y-12160D03*
X-1505063Y-22160D03*
X-1510063D03*
X-1505063Y-17160D03*
Y-12160D03*
X-1510063Y-17160D03*
Y-12160D03*
X-1500063Y-22160D03*
Y-17160D03*
Y-12160D03*
X-1520063Y-22160D03*
X-1525063D03*
X-1520063Y-17160D03*
Y-12160D03*
X-1525063Y-17160D03*
Y-12160D03*
X-1515063Y-22160D03*
Y-17160D03*
Y-12160D03*
X-1535063Y-17160D03*
Y-12160D03*
X-1530063Y-22160D03*
Y-17160D03*
Y-12160D03*
X-1535063Y-22160D03*
X-1124700Y-180000D03*
X-1124878Y-175150D03*
X-1124900Y-170650D03*
X-1114979Y-170700D03*
X-1106979D03*
X-1095600Y-179600D03*
X-1096278Y-170650D03*
X-1096200Y-175150D03*
X-254800Y-180000D03*
Y-170650D03*
X-254800Y-175150D03*
X-244900Y-170700D03*
X-225400Y-179800D03*
X-226200Y-170650D03*
X-226121Y-175150D03*
X-236900Y-170700D03*
X-152400Y-125050D03*
X-150900Y-121100D03*
G54D29*
X-412402Y-23858D03*
Y-59291D03*
Y-94724D03*
Y-130157D03*
X-1207677Y-6142D03*
Y-41575D03*
Y-77008D03*
Y-112441D03*
X-1282480Y-23858D03*
Y-59291D03*
Y-94724D03*
Y-130157D03*
G54D34*
X-938386Y1459D03*
Y-50942D03*
X-954134Y-105312D03*
X-981693Y1459D03*
Y-50942D03*
X-997441Y-105312D03*
X-1025000Y1459D03*
Y-50942D03*
G54D39*
X-78150Y-53698D03*
Y-68659D03*
Y-83620D03*
X-81102Y-48187D03*
Y-63147D03*
Y-78108D03*
Y-93068D03*
X-124409Y-48187D03*
X-121457Y-53698D03*
X-124409Y-63147D03*
X-121457Y-68659D03*
X-124409Y-78108D03*
X-121457Y-83620D03*
X-124409Y-93068D03*
X-121457Y-98580D03*
X-78150D03*
G54D33*
X-793728Y-146102D03*
Y-153976D03*
G54D30*
X-449803Y-127795D03*
Y-135669D03*
Y-159291D03*
Y-167165D03*
Y-175039D03*
X-457677Y-127795D03*
Y-135669D03*
Y-143543D03*
Y-159291D03*
Y-167165D03*
Y-175039D03*
X-793728Y-138228D03*
Y-161850D03*
X-1319882Y-127795D03*
Y-135669D03*
Y-159291D03*
Y-167165D03*
Y-175039D03*
X-1327756Y-127795D03*
Y-135669D03*
Y-143543D03*
Y-159291D03*
Y-167165D03*
Y-175039D03*
G54D38*
X-1278150Y-142362D03*
G54D35*
X-1085138Y-94331D03*
G54D32*
X-785200Y-99635D03*
X-806854D03*
X-1085138Y-4567D03*
Y-43937D03*
Y-83307D03*
X-1107500D03*
X-1118917Y-4567D03*
X-1128760Y-83307D03*
X-1141240Y-24252D03*
Y-63622D03*
G54D31*
X-785200Y-83100D03*
X-806854D03*
G54D37*
X-1410000Y0D03*
G54D36*
X-486810Y-118937D03*
X-1051613D03*
%LPD*%
G75*
G54D10*
X-1618400Y-71600D03*
X-1618500Y-67200D03*
X-1621600Y-69400D03*
X-1615000Y-37500D03*
Y-27500D03*
Y-32500D03*
X-1610000Y-37500D03*
Y-32500D03*
Y-27500D03*
X-1600000Y-37500D03*
Y-27500D03*
Y-32500D03*
X-1605000Y-37500D03*
Y-32500D03*
Y-27500D03*
X-1595000Y-37500D03*
Y-32500D03*
Y-27500D03*
X-1580000Y-42500D03*
Y-47500D03*
X-1585000Y-42500D03*
Y-47500D03*
X-1590000D03*
Y-42500D03*
X-1580000Y-27500D03*
Y-32500D03*
Y-37500D03*
X-1585000Y-32500D03*
Y-27500D03*
Y-37500D03*
X-1590000D03*
Y-32500D03*
Y-27500D03*
X-1565000Y-42500D03*
Y-47500D03*
X-1575000Y-42500D03*
Y-47500D03*
X-1570000Y-42500D03*
Y-47500D03*
X-1565000Y-27500D03*
Y-32500D03*
Y-37500D03*
X-1575000Y-27500D03*
Y-32500D03*
Y-37500D03*
X-1570000Y-32500D03*
Y-27500D03*
Y-37500D03*
X-1555000Y-47500D03*
Y-42500D03*
X-1550000Y-47500D03*
Y-42500D03*
X-1560000D03*
Y-47500D03*
X-1545000D03*
Y-42500D03*
Y-37500D03*
Y-32500D03*
Y-27500D03*
X-1555000Y-37500D03*
Y-32500D03*
Y-27500D03*
X-1550000Y-37500D03*
Y-32500D03*
Y-27500D03*
X-1560000D03*
Y-32500D03*
Y-37500D03*
X-1530000Y-120300D03*
X-1535000Y-42500D03*
Y-47500D03*
X-1540000Y-42500D03*
Y-47500D03*
Y-37500D03*
Y-32500D03*
X-1535000Y-37500D03*
Y-32500D03*
X-1476693Y-71890D03*
X-1481693D03*
X-1471693D03*
X-1476693Y-76890D03*
X-1481693D03*
X-1471693D03*
X-1466693D03*
Y-81890D03*
Y-71890D03*
X-1461693D03*
Y-76890D03*
X-1450000Y-175000D03*
X-1437500Y-162500D03*
X-1450000Y-150000D03*
Y-125000D03*
X-1443500Y-94000D03*
X-1450000Y-100000D03*
X-1434892Y-40389D03*
Y-50389D03*
Y-45389D03*
Y-35389D03*
X-1425000Y-175000D03*
X-1424500Y-100000D03*
X-1425000Y-87500D03*
Y-62500D03*
X-1419892Y-50389D03*
Y-40389D03*
Y-45389D03*
X-1427392Y-50389D03*
Y-45389D03*
Y-40389D03*
X-1419892Y-35389D03*
X-1427392D03*
X-1432000Y-18000D03*
X-1412500Y-162500D03*
X-1412000Y-87000D03*
X-1412500Y-75000D03*
X-1404892Y-50389D03*
Y-45389D03*
Y-40389D03*
X-1412392Y-50389D03*
Y-45389D03*
Y-40389D03*
X-1404892Y-35389D03*
X-1412392D03*
X-1407000Y-18000D03*
X-1407500Y14500D03*
X-1400000Y-175000D03*
X-1387500Y-162500D03*
X-1400000Y-150000D03*
X-1387500Y-137500D03*
X-1400000Y-125000D03*
X-1387500Y-112500D03*
X-1400500Y-87000D03*
X-1391000Y-96500D03*
X-1387500Y-75000D03*
X-1400000Y-62500D03*
X-1389892Y-40389D03*
Y-45389D03*
Y-50389D03*
X-1397392Y-40389D03*
Y-45389D03*
Y-50389D03*
X-1389892Y-35389D03*
X-1397392D03*
X-1395000Y-8000D03*
X-1375000Y-62500D03*
X-1382392Y-40389D03*
Y-45389D03*
Y-50389D03*
Y-35389D03*
X-1382500Y-18000D03*
Y-500D03*
Y14500D03*
X-1362500Y-75000D03*
X-1370000Y-8000D03*
X-1357500Y-500D03*
X-1370000Y7000D03*
X-1357500Y14500D03*
X-1350000Y-62500D03*
X-1345000Y-8000D03*
Y7000D03*
X-1335400Y-75000D03*
Y-37600D03*
X-1332500Y-500D03*
Y14500D03*
X-1322228Y-88400D03*
X-1316728Y-89200D03*
X-1320000Y7000D03*
X-1293500Y-80000D03*
X-1307500Y14500D03*
X-1282500D03*
X-1250591Y-179920D03*
X-1257500Y-45000D03*
Y-20000D03*
Y14500D03*
X-1232500Y-20000D03*
Y14500D03*
X-1202580Y-176300D03*
X-1199500Y-3000D03*
X-1207500Y14500D03*
X-1182500D03*
X-1151500Y-15000D03*
X-1157500Y14500D03*
X-1137500Y-15000D03*
X-1134579Y-179850D03*
X-1126000Y-2500D03*
X-1132500Y14500D03*
X-1113328Y-182209D03*
X-1107828Y-182300D03*
X-1111500Y-15000D03*
X-1107500Y14500D03*
X-1100000Y-2500D03*
X-1084600Y-179850D03*
X-1082500Y14500D03*
X-1070000D03*
X-1045000D03*
X-1020000D03*
X-997500Y-7500D03*
X-995000Y14500D03*
X-970000Y-7500D03*
Y14500D03*
X-945000Y-7500D03*
Y14500D03*
X-922500Y-159500D03*
Y-132500D03*
Y-107500D03*
Y-82500D03*
Y-57500D03*
Y-7500D03*
X-922000Y14500D03*
X-910000Y-170000D03*
Y-95000D03*
Y-70000D03*
Y-45000D03*
Y-20000D03*
Y5000D03*
X-885000Y-170000D03*
X-897500Y-159500D03*
Y-132500D03*
Y-107500D03*
X-885000Y-95000D03*
X-897500Y-82500D03*
X-885000Y-70000D03*
X-897500Y-57500D03*
X-885000Y-45000D03*
Y-20000D03*
X-897500Y-7500D03*
X-885000Y5000D03*
X-897500Y14500D03*
X-872500Y-159500D03*
Y-132500D03*
Y-107500D03*
Y-82500D03*
Y-57500D03*
Y-7500D03*
Y14500D03*
X-860000Y-170000D03*
Y-95000D03*
Y-70000D03*
Y-45000D03*
Y-20000D03*
Y5000D03*
X-847500Y-159500D03*
Y-132500D03*
Y-107500D03*
Y-82500D03*
Y-57500D03*
Y-7500D03*
X-848000Y14500D03*
X-822500Y-159500D03*
Y-132500D03*
X-835000Y-120000D03*
X-822500Y-107500D03*
X-835000Y-95000D03*
X-822500Y-82500D03*
X-835000Y-70000D03*
X-822500Y-57500D03*
X-835000Y-45000D03*
X-822500Y-7500D03*
X-835000Y-20000D03*
X-822500Y14500D03*
X-810000Y-20000D03*
Y5000D03*
X-797500Y-7500D03*
Y14500D03*
X-785000Y-20000D03*
Y5000D03*
X-760000Y-145000D03*
X-772500Y-132500D03*
X-760000Y-120000D03*
X-772500Y-107500D03*
X-760000Y-95000D03*
X-772500Y-82500D03*
X-760000Y-70000D03*
X-772500Y-57500D03*
X-760000Y-45000D03*
Y-20000D03*
X-772500Y-7500D03*
X-760000Y5000D03*
X-772500Y14500D03*
X-747500Y-57500D03*
Y-7500D03*
Y14500D03*
X-735000Y-45000D03*
Y-20000D03*
Y5000D03*
X-722500Y-57500D03*
Y-7500D03*
Y14500D03*
X-710000Y-45000D03*
X-697500Y-7500D03*
X-710000Y-20000D03*
Y5000D03*
X-697500Y14500D03*
X-685000Y-45000D03*
Y-20000D03*
Y5000D03*
X-672500Y-7500D03*
Y14500D03*
X-649700Y-117200D03*
X-655500Y-25500D03*
X-642500D03*
Y-37500D03*
Y-12500D03*
X-645000Y14500D03*
X-630000Y-37500D03*
X-616000Y-25500D03*
X-606614Y-71890D03*
X-611614D03*
X-601614D03*
X-606614Y-76890D03*
X-611614D03*
X-601614D03*
X-602500Y-25000D03*
Y0D03*
X-591614Y-71890D03*
X-596614Y-76890D03*
Y-81890D03*
X-591614Y-76890D03*
X-596614Y-71890D03*
X-590000Y-37500D03*
Y-12500D03*
Y12500D03*
X-577500Y-165000D03*
Y-140000D03*
Y-115000D03*
Y-65000D03*
Y-25000D03*
Y0D03*
X-565000Y-177500D03*
Y-152500D03*
Y-37500D03*
Y-12500D03*
Y12500D03*
X-540000Y-177500D03*
X-552500Y-165000D03*
X-540000Y-152500D03*
X-552500Y-140000D03*
X-540000Y-127500D03*
Y-102500D03*
Y-77500D03*
X-552500Y-65000D03*
Y-25000D03*
X-540000Y-37500D03*
Y-12500D03*
X-552500Y0D03*
X-540000Y12500D03*
X-527500Y-165000D03*
Y-140000D03*
Y-115000D03*
Y-90000D03*
Y-65000D03*
Y-25000D03*
Y0D03*
X-515000Y-177500D03*
Y-152500D03*
Y-127500D03*
Y-102500D03*
Y-77500D03*
Y-37500D03*
Y-12500D03*
Y12500D03*
X-490000Y-102500D03*
X-502500Y-90000D03*
X-490000Y-77500D03*
X-502500Y-65000D03*
X-490000Y-37500D03*
X-502500Y-25000D03*
X-490000Y-12500D03*
X-502500Y0D03*
X-490000Y12500D03*
X-477500Y-25000D03*
Y0D03*
X-462000Y-73500D03*
X-465000Y-37500D03*
Y12500D03*
X-453628Y-88300D03*
X-448128Y-88800D03*
X-449000Y6500D03*
X-431000D03*
X-440000Y12500D03*
X-424500Y-26500D03*
X-371063Y-178998D03*
X-374213Y-177998D03*
X-375800Y-154000D03*
X-374800Y-105700D03*
X-265200Y-179850D03*
X-237750Y-182300D03*
X-243250Y-182209D03*
X-214500Y-179800D03*
X-196900Y-176500D03*
X-201600Y-176600D03*
X-206100D03*
X-191000Y-56400D03*
X-190300Y-28900D03*
Y-4200D03*
X-185900Y-56200D03*
X-182900Y-29800D03*
X-183200Y-4600D03*
X-145650Y-100550D03*
X-145100Y-74100D03*
X-152500Y12500D03*
X-138440Y-91390D03*
X-133301Y-86986D03*
X-142559Y-85886D03*
X-129882Y-90706D03*
X-129782Y-75998D03*
X-138640D03*
X-142559Y-70873D03*
X-133701Y-56060D03*
X-129782Y-60885D03*
X-142559Y-56060D03*
X-142130Y-41290D03*
X-139000Y-8500D03*
Y-21000D03*
X-140000Y12500D03*
X-127500D03*
X-126600Y-75410D03*
X-124590Y-41500D03*
X-114000Y-33500D03*
X-126500Y-21000D03*
X-114000Y-8500D03*
Y-21000D03*
X-126500Y-8500D03*
X-115000Y12500D03*
X-99252Y-100849D03*
Y-85886D03*
X-101700Y-73800D03*
X-101500Y-33500D03*
Y-21000D03*
Y-8500D03*
X-102500Y12500D03*
X-95433Y-90706D03*
X-86575D03*
X-90194Y-101049D03*
X-83310Y-75360D03*
X-95333Y-75848D03*
X-86475D03*
Y-60885D03*
X-87700Y-57700D03*
X-95333Y-45922D03*
X-86475D03*
X-89000Y-8500D03*
Y-21000D03*
X-90000Y12500D03*
X-74921Y-171500D03*
X-71500Y-158500D03*
Y-146000D03*
Y-133500D03*
X-71700Y-121000D03*
X-70500Y-108600D03*
X-76500Y-33500D03*
Y-21000D03*
Y-8500D03*
X-77500Y12500D03*
X-65000D03*
G54D20*
G01X-1186050Y-540000D02*
Y-552500D01*
X-1180250D01*
G01X-1174975D02*
X-1171350Y-540000D01*
X-1167725Y-552500D01*
G01X-1169030Y-548125D02*
X-1173670D01*
G01X-1159550Y-552500D02*
Y-546875D01*
X-1162450Y-540000D01*
G01X-1156650D02*
X-1159550Y-546875D01*
G01X-1144850Y-552500D02*
X-1150650D01*
Y-540000D01*
X-1144850D01*
G01X-1147170Y-546042D02*
X-1150650D01*
G01X-1138850Y-552500D02*
Y-540000D01*
X-1135225D01*
X-1134065Y-540625D01*
X-1133340Y-541458D01*
X-1133050Y-543125D01*
X-1133340Y-544792D01*
X-1134210Y-545833D01*
X-1135225Y-546458D01*
X-1138850D01*
G01X-1135225D02*
X-1133050Y-552500D01*
G01X-1110610D02*
Y-540000D01*
X-1115975Y-548958D01*
X-1108725D01*
G54D11*
X-1600236Y-134488D03*
Y-140000D03*
X-1592362Y-139606D03*
X-1584488Y-134488D03*
Y-140000D03*
X-1576614Y-139606D03*
Y-145118D03*
X-1568740Y-134488D03*
Y-140000D03*
X-1560866Y-139606D03*
Y-145118D03*
X-1552992Y-134488D03*
Y-140000D03*
X-1545118Y-139606D03*
Y-145118D03*
X-1189134Y-156535D03*
Y-162047D03*
X-1173386Y-134488D03*
X-714409D03*
X-722283Y-139606D03*
X-714409Y-140000D03*
X-698661Y-134488D03*
X-706535Y-139606D03*
X-698661Y-140000D03*
X-706535Y-145118D03*
X-682913Y-134488D03*
X-690787Y-139606D03*
X-682913Y-140000D03*
X-690787Y-145118D03*
X-675039Y-139606D03*
Y-145118D03*
X-319055Y-156535D03*
Y-162047D03*
X-303307Y-134488D03*
X-144409Y-178976D03*
Y-162441D03*
Y-145906D03*
Y-129370D03*
X-136535Y-167559D03*
X-128661Y-178976D03*
X-136535Y-151024D03*
X-128661Y-162441D03*
X-136535Y-134488D03*
X-128661Y-145906D03*
Y-129370D03*
X-120787Y-167559D03*
X-112913Y-178976D03*
X-120787Y-151024D03*
X-112913Y-162441D03*
X-120787Y-134488D03*
X-112913Y-145906D03*
Y-129370D03*
X-105039Y-167559D03*
Y-151024D03*
Y-134488D03*
G54D21*
G01X-1185925Y-592500D02*
X-1178575Y-577500D01*
G01X-1185925D02*
X-1178575Y-592500D01*
G01X-1168050D02*
X-1166825Y-592250D01*
X-1165425Y-591500D01*
X-1164550Y-590250D01*
X-1164200Y-588500D01*
X-1164550Y-586750D01*
X-1165600Y-585250D01*
X-1167175Y-584500D01*
X-1168925D01*
X-1169975Y-584000D01*
X-1170850Y-582750D01*
X-1171200Y-581000D01*
X-1170675Y-579250D01*
X-1169450Y-578000D01*
X-1168050Y-577500D01*
X-1166650Y-578000D01*
X-1165425Y-579250D01*
X-1164900Y-581000D01*
X-1165250Y-582750D01*
X-1166125Y-584000D01*
X-1167175Y-584500D01*
X-1168925D01*
X-1170500Y-585250D01*
X-1171550Y-586750D01*
X-1171900Y-588500D01*
X-1171550Y-590250D01*
X-1170675Y-591500D01*
X-1169275Y-592250D01*
X-1168050Y-592500D01*
G01X-1153850D02*
X-1152625Y-592250D01*
X-1151225Y-591500D01*
X-1150350Y-590250D01*
X-1150000Y-588500D01*
X-1150350Y-586750D01*
X-1151400Y-585250D01*
X-1152975Y-584500D01*
X-1154725D01*
X-1155775Y-584000D01*
X-1156650Y-582750D01*
X-1157000Y-581000D01*
X-1156475Y-579250D01*
X-1155250Y-578000D01*
X-1153850Y-577500D01*
X-1152450Y-578000D01*
X-1151225Y-579250D01*
X-1150700Y-581000D01*
X-1151050Y-582750D01*
X-1151925Y-584000D01*
X-1152975Y-584500D01*
X-1154725D01*
X-1156300Y-585250D01*
X-1157350Y-586750D01*
X-1157700Y-588500D01*
X-1157350Y-590250D01*
X-1156475Y-591500D01*
X-1155075Y-592250D01*
X-1153850Y-592500D01*
G01X-1140000D02*
X-1139650Y-589250D01*
X-1139125Y-586500D01*
X-1138425Y-584000D01*
X-1137550Y-581250D01*
X-1136150Y-577500D01*
X-1143150D01*
G01X-1129300Y-590250D02*
X-1128250Y-591500D01*
X-1127025Y-592250D01*
X-1125450Y-592500D01*
X-1123875Y-592000D01*
X-1122650Y-591000D01*
X-1121775Y-589250D01*
X-1121600Y-587250D01*
X-1121950Y-585250D01*
X-1122825Y-584000D01*
X-1124050Y-583000D01*
X-1125275Y-582750D01*
X-1126500Y-583000D01*
X-1128075Y-584000D01*
X-1127550Y-577500D01*
X-1122825D01*
G01X-1111600Y-592500D02*
X-1111250Y-589250D01*
X-1110725Y-586500D01*
X-1110025Y-584000D01*
X-1109150Y-581250D01*
X-1107750Y-577500D01*
X-1114750D01*
G01X-1097050Y-592500D02*
Y-577500D01*
X-1099150Y-580500D01*
G01Y-592500D02*
X-1094950D01*
G01X-1085125Y-587500D02*
X-1080575D01*
G01X-1068650Y-577500D02*
X-1070050Y-578000D01*
X-1071100Y-579250D01*
X-1071800Y-580750D01*
X-1072325Y-582750D01*
X-1072500Y-585000D01*
X-1072325Y-587250D01*
X-1071800Y-589250D01*
X-1071100Y-590750D01*
X-1070050Y-592000D01*
X-1068650Y-592500D01*
X-1067250Y-592000D01*
X-1066200Y-590750D01*
X-1065500Y-589250D01*
X-1064975Y-587250D01*
X-1064800Y-585000D01*
X-1064975Y-582750D01*
X-1065500Y-580750D01*
X-1066200Y-579250D01*
X-1067250Y-578000D01*
X-1068650Y-577500D01*
G01X-1054450D02*
X-1055850Y-578000D01*
X-1056900Y-579250D01*
X-1057600Y-580750D01*
X-1058125Y-582750D01*
X-1058300Y-585000D01*
X-1058125Y-587250D01*
X-1057600Y-589250D01*
X-1056900Y-590750D01*
X-1055850Y-592000D01*
X-1054450Y-592500D01*
X-1053050Y-592000D01*
X-1052000Y-590750D01*
X-1051300Y-589250D01*
X-1050775Y-587250D01*
X-1050600Y-585000D01*
X-1050775Y-582750D01*
X-1051300Y-580750D01*
X-1052000Y-579250D01*
X-1053050Y-578000D01*
X-1054450Y-577500D01*
G01X-1044100Y-590250D02*
X-1043050Y-591500D01*
X-1041825Y-592250D01*
X-1040250Y-592500D01*
X-1038675Y-592000D01*
X-1037450Y-591000D01*
X-1036575Y-589250D01*
X-1036400Y-587250D01*
X-1036750Y-585250D01*
X-1037625Y-584000D01*
X-1038850Y-583000D01*
X-1040075Y-582750D01*
X-1041300Y-583000D01*
X-1042875Y-584000D01*
X-1042350Y-577500D01*
X-1037625D01*
G01X-911875Y-592500D02*
X-907500Y-577500D01*
X-903125Y-592500D01*
G01X-904700Y-587250D02*
X-910300D01*
G01X-810781Y-87027D02*
X-806854Y-83100D01*
G01D02*
X-802927Y-79173D01*
G01X-810781D02*
X-806854Y-83100D01*
G01D02*
X-802927Y-87027D01*
G01X-789127D02*
X-785200Y-83100D01*
G01X-789127Y-79173D02*
X-785200Y-83100D01*
G01D02*
X-781273Y-87027D01*
G01X-785200Y-83100D02*
X-781273Y-79173D01*
G54D12*
X-1356889Y-167165D03*
Y-118937D03*
X-1051613Y-167165D03*
Y-118937D03*
X-486810Y-167165D03*
Y-118937D03*
X-181534Y-167165D03*
Y-118937D03*
G54D22*
G01X-1200000Y-560000D02*
X-890000D01*
G01Y-520000D02*
X-1200000D01*
G01X-575000Y-480000D02*
X-1200000D01*
G01X-927500Y-560000D02*
Y-600000D01*
G01X-915000Y-440000D02*
Y-480000D01*
G01X-890000D02*
Y-600000D01*
G01X-870000Y-440000D02*
Y-480000D01*
G01X-680000D02*
Y-440000D01*
G01X-1200000Y-600000D02*
X-575000D01*
Y-440000D01*
X-1200000D01*
Y-600000D01*
G54D13*
X-1296260Y-175039D03*
X-1304134D03*
X-1296260Y-167165D03*
X-1304134D03*
X-1296260Y-159291D03*
X-1304134D03*
X-1296260Y-143543D03*
X-1304134D03*
X-1296260Y-135669D03*
X-1304134D03*
X-1296260Y-127795D03*
X-1304134D03*
X-426181Y-175039D03*
X-434055D03*
X-426181Y-167165D03*
X-434055D03*
X-426181Y-159291D03*
X-434055D03*
X-426181Y-143543D03*
X-434055D03*
X-426181Y-135669D03*
X-434055D03*
X-426181Y-127795D03*
X-434055D03*
G54D23*
G01X-1007500Y-470000D02*
X-1006450Y-475000D01*
X-1005250Y-470000D01*
X-1004050Y-475000D01*
X-1003000Y-470000D01*
G01X-1001125Y-475000D02*
X-999250Y-470000D01*
X-997375Y-475000D01*
G01X-998050Y-473250D02*
X-1000450D01*
G01X-994825Y-474333D02*
X-994225Y-474750D01*
X-993550Y-475000D01*
X-992950D01*
X-992350Y-474750D01*
X-991900Y-474333D01*
X-991675Y-473750D01*
X-991825Y-473167D01*
X-992200Y-472667D01*
X-992875Y-472333D01*
X-993775Y-472167D01*
X-994300Y-471833D01*
X-994525Y-471250D01*
X-994375Y-470667D01*
X-994000Y-470250D01*
X-993475Y-470000D01*
X-992950D01*
X-992425Y-470167D01*
X-991975Y-470583D01*
G01X-988825Y-475000D02*
Y-470000D01*
G01X-985675D02*
Y-475000D01*
G01Y-472500D02*
X-988825D01*
G01X-976525Y-474417D02*
X-976000Y-474833D01*
X-975400Y-475000D01*
X-974800Y-474833D01*
X-974275Y-474333D01*
X-973900Y-473583D01*
X-973750Y-472833D01*
Y-471917D01*
X-973900Y-471167D01*
X-974275Y-470500D01*
X-974725Y-470167D01*
X-975250Y-470000D01*
X-975850Y-470167D01*
X-976300Y-470500D01*
X-976600Y-471000D01*
X-976750Y-471667D01*
X-976600Y-472250D01*
X-976225Y-472833D01*
X-975775Y-473167D01*
X-975250Y-473250D01*
X-974650Y-473083D01*
X-974200Y-472667D01*
X-973750Y-471917D01*
G01X-969250Y-475000D02*
X-968725Y-474917D01*
X-968125Y-474667D01*
X-967750Y-474250D01*
X-967600Y-473667D01*
X-967750Y-473083D01*
X-968200Y-472583D01*
X-968875Y-472333D01*
X-969625D01*
X-970075Y-472167D01*
X-970450Y-471750D01*
X-970600Y-471167D01*
X-970375Y-470583D01*
X-969850Y-470167D01*
X-969250Y-470000D01*
X-968650Y-470167D01*
X-968125Y-470583D01*
X-967900Y-471167D01*
X-968050Y-471750D01*
X-968425Y-472167D01*
X-968875Y-472333D01*
X-969625D01*
X-970300Y-472583D01*
X-970750Y-473083D01*
X-970900Y-473667D01*
X-970750Y-474250D01*
X-970375Y-474667D01*
X-969775Y-474917D01*
X-969250Y-475000D01*
G01X-963250Y-470000D02*
X-963850Y-470167D01*
X-964300Y-470583D01*
X-964600Y-471083D01*
X-964825Y-471750D01*
X-964900Y-472500D01*
X-964825Y-473250D01*
X-964600Y-473917D01*
X-964300Y-474417D01*
X-963850Y-474833D01*
X-963250Y-475000D01*
X-962650Y-474833D01*
X-962200Y-474417D01*
X-961900Y-473917D01*
X-961675Y-473250D01*
X-961600Y-472500D01*
X-961675Y-471750D01*
X-961900Y-471083D01*
X-962200Y-470583D01*
X-962650Y-470167D01*
X-963250Y-470000D01*
G01X-958900Y-474250D02*
X-958450Y-474667D01*
X-957925Y-474917D01*
X-957250Y-475000D01*
X-956575Y-474833D01*
X-956050Y-474500D01*
X-955675Y-473917D01*
X-955600Y-473250D01*
X-955750Y-472583D01*
X-956125Y-472167D01*
X-956650Y-471833D01*
X-957175Y-471750D01*
X-957700Y-471833D01*
X-958375Y-472167D01*
X-958150Y-470000D01*
X-956125D01*
G01X-952675Y-470833D02*
X-952225Y-470333D01*
X-951700Y-470083D01*
X-951100Y-470000D01*
X-950350Y-470167D01*
X-949825Y-470583D01*
X-949675Y-471083D01*
X-949750Y-471583D01*
X-950050Y-472000D01*
X-951550Y-472833D01*
X-952225Y-473417D01*
X-952675Y-474250D01*
X-952825Y-475000D01*
X-949675D01*
G01X-946225Y-473333D02*
X-944275D01*
G01X-940675Y-472917D02*
X-940150Y-472333D01*
X-939700Y-472000D01*
X-939100Y-471833D01*
X-938575Y-472000D01*
X-938200Y-472333D01*
X-937900Y-472833D01*
X-937825Y-473417D01*
X-937900Y-473917D01*
X-938200Y-474417D01*
X-938650Y-474833D01*
X-939175Y-475000D01*
X-939775Y-474833D01*
X-940300Y-474333D01*
X-940600Y-473583D01*
X-940675Y-472750D01*
X-940525Y-471667D01*
X-940300Y-471083D01*
X-939925Y-470500D01*
X-939400Y-470083D01*
X-938875Y-470000D01*
X-938350Y-470167D01*
X-937975Y-470583D01*
G01X-934900Y-474000D02*
X-934450Y-474583D01*
X-933850Y-474917D01*
X-933175Y-475000D01*
X-932575Y-474917D01*
X-931975Y-474500D01*
X-931600Y-474000D01*
X-931525Y-473500D01*
X-931675Y-472917D01*
X-932200Y-472500D01*
X-932725Y-472333D01*
X-933400D01*
G01X-932725D02*
X-932275Y-472083D01*
X-931900Y-471667D01*
X-931750Y-471167D01*
X-931900Y-470667D01*
X-932275Y-470250D01*
X-932950Y-470000D01*
X-933625Y-470083D01*
X-934300Y-470417D01*
G01X-928525Y-474417D02*
X-928000Y-474833D01*
X-927400Y-475000D01*
X-926800Y-474833D01*
X-926275Y-474333D01*
X-925900Y-473583D01*
X-925750Y-472833D01*
Y-471917D01*
X-925900Y-471167D01*
X-926275Y-470500D01*
X-926725Y-470167D01*
X-927250Y-470000D01*
X-927850Y-470167D01*
X-928300Y-470500D01*
X-928600Y-471000D01*
X-928750Y-471667D01*
X-928600Y-472250D01*
X-928225Y-472833D01*
X-927775Y-473167D01*
X-927250Y-473250D01*
X-926650Y-473083D01*
X-926200Y-472667D01*
X-925750Y-471917D01*
G01X-922525Y-474417D02*
X-922000Y-474833D01*
X-921400Y-475000D01*
X-920800Y-474833D01*
X-920275Y-474333D01*
X-919900Y-473583D01*
X-919750Y-472833D01*
Y-471917D01*
X-919900Y-471167D01*
X-920275Y-470500D01*
X-920725Y-470167D01*
X-921250Y-470000D01*
X-921850Y-470167D01*
X-922300Y-470500D01*
X-922600Y-471000D01*
X-922750Y-471667D01*
X-922600Y-472250D01*
X-922225Y-472833D01*
X-921775Y-473167D01*
X-921250Y-473250D01*
X-920650Y-473083D01*
X-920200Y-472667D01*
X-919750Y-471917D01*
G01X-1006750Y-465000D02*
Y-460000D01*
X-1004875D01*
X-1004275Y-460250D01*
X-1003900Y-460583D01*
X-1003750Y-461250D01*
X-1003900Y-461917D01*
X-1004350Y-462333D01*
X-1004875Y-462583D01*
X-1006750D01*
G01X-1004875D02*
X-1003750Y-465000D01*
G01X-997750D02*
X-1000750D01*
Y-460000D01*
X-997750D01*
G01X-998950Y-462417D02*
X-1000750D01*
G01X-994900Y-465000D02*
Y-460000D01*
X-993400D01*
X-992800Y-460250D01*
X-992350Y-460583D01*
X-991975Y-461083D01*
X-991675Y-461667D01*
X-991600Y-462500D01*
X-991675Y-463333D01*
X-991975Y-463917D01*
X-992350Y-464417D01*
X-992800Y-464750D01*
X-993400Y-465000D01*
X-994900D01*
G01X-989200D02*
Y-460000D01*
X-987250Y-464167D01*
X-985300Y-460000D01*
Y-465000D01*
G01X-981250D02*
X-981850Y-464917D01*
X-982375Y-464583D01*
X-982825Y-464083D01*
X-983125Y-463500D01*
X-983275Y-462833D01*
Y-462167D01*
X-983125Y-461500D01*
X-982825Y-460917D01*
X-982375Y-460417D01*
X-981850Y-460083D01*
X-981250Y-460000D01*
X-980650Y-460083D01*
X-980125Y-460417D01*
X-979675Y-460917D01*
X-979375Y-461500D01*
X-979225Y-462167D01*
Y-462833D01*
X-979375Y-463500D01*
X-979675Y-464083D01*
X-980125Y-464583D01*
X-980650Y-464917D01*
X-981250Y-465000D01*
G01X-976975D02*
Y-460000D01*
X-973525Y-465000D01*
Y-460000D01*
G01X-970900Y-465000D02*
Y-460000D01*
X-969400D01*
X-968800Y-460250D01*
X-968350Y-460583D01*
X-967975Y-461083D01*
X-967675Y-461667D01*
X-967600Y-462500D01*
X-967675Y-463333D01*
X-967975Y-463917D01*
X-968350Y-464417D01*
X-968800Y-464750D01*
X-969400Y-465000D01*
X-970900D01*
G01X-1005250Y-455000D02*
Y-450000D01*
X-1006150Y-451000D01*
G01Y-455000D02*
X-1004350D01*
G01X-995200D02*
Y-450000D01*
X-993250Y-454167D01*
X-991300Y-450000D01*
Y-455000D01*
G01X-988150Y-450000D02*
X-986350D01*
G01X-987250D02*
Y-455000D01*
G01X-988150D02*
X-986350D01*
G01X-979600Y-450417D02*
X-980050Y-450167D01*
X-980575Y-450000D01*
X-981175D01*
X-981850Y-450250D01*
X-982375Y-450667D01*
X-982750Y-451167D01*
X-983050Y-452000D01*
X-983125Y-452750D01*
X-982975Y-453500D01*
X-982750Y-454000D01*
X-982300Y-454500D01*
X-981775Y-454833D01*
X-981250Y-455000D01*
X-980725D01*
X-980200Y-454833D01*
X-979750Y-454583D01*
X-979375Y-454250D01*
G01X-976750Y-455000D02*
Y-450000D01*
X-974875D01*
X-974275Y-450250D01*
X-973900Y-450583D01*
X-973750Y-451250D01*
X-973900Y-451917D01*
X-974350Y-452333D01*
X-974875Y-452583D01*
X-976750D01*
G01X-974875D02*
X-973750Y-455000D01*
G01X-969250D02*
X-969850Y-454917D01*
X-970375Y-454583D01*
X-970825Y-454083D01*
X-971125Y-453500D01*
X-971275Y-452833D01*
Y-452167D01*
X-971125Y-451500D01*
X-970825Y-450917D01*
X-970375Y-450417D01*
X-969850Y-450083D01*
X-969250Y-450000D01*
X-968650Y-450083D01*
X-968125Y-450417D01*
X-967675Y-450917D01*
X-967375Y-451500D01*
X-967225Y-452167D01*
Y-452833D01*
X-967375Y-453500D01*
X-967675Y-454083D01*
X-968125Y-454583D01*
X-968650Y-454917D01*
X-969250Y-455000D01*
G01X-964825Y-454333D02*
X-964225Y-454750D01*
X-963550Y-455000D01*
X-962950D01*
X-962350Y-454750D01*
X-961900Y-454333D01*
X-961675Y-453750D01*
X-961825Y-453167D01*
X-962200Y-452667D01*
X-962875Y-452333D01*
X-963775Y-452167D01*
X-964300Y-451833D01*
X-964525Y-451250D01*
X-964375Y-450667D01*
X-964000Y-450250D01*
X-963475Y-450000D01*
X-962950D01*
X-962425Y-450167D01*
X-961975Y-450583D01*
G01X-957250Y-455000D02*
X-957850Y-454917D01*
X-958375Y-454583D01*
X-958825Y-454083D01*
X-959125Y-453500D01*
X-959275Y-452833D01*
Y-452167D01*
X-959125Y-451500D01*
X-958825Y-450917D01*
X-958375Y-450417D01*
X-957850Y-450083D01*
X-957250Y-450000D01*
X-956650Y-450083D01*
X-956125Y-450417D01*
X-955675Y-450917D01*
X-955375Y-451500D01*
X-955225Y-452167D01*
Y-452833D01*
X-955375Y-453500D01*
X-955675Y-454083D01*
X-956125Y-454583D01*
X-956650Y-454917D01*
X-957250Y-455000D01*
G01X-952675D02*
Y-450000D01*
X-949825D01*
G01X-950875Y-452417D02*
X-952675D01*
G01X-945250Y-450000D02*
Y-455000D01*
G01X-946975Y-450000D02*
X-943525D01*
G01X-935500D02*
X-934450Y-455000D01*
X-933250Y-450000D01*
X-932050Y-455000D01*
X-931000Y-450000D01*
G01X-929125Y-455000D02*
X-927250Y-450000D01*
X-925375Y-455000D01*
G01X-926050Y-453250D02*
X-928450D01*
G01X-921250Y-455000D02*
Y-452750D01*
X-922750Y-450000D01*
G01X-919750D02*
X-921250Y-452750D01*
G54D14*
X-806854Y-83100D03*
X-785200D03*
G54D24*
G01X-874510Y-499000D02*
Y-493000D01*
X-871290Y-499000D01*
Y-493000D01*
G01X-867200Y-499000D02*
X-867760Y-498900D01*
X-868250Y-498500D01*
X-868670Y-497900D01*
X-868950Y-497200D01*
X-869090Y-496400D01*
Y-495600D01*
X-868950Y-494800D01*
X-868670Y-494100D01*
X-868250Y-493500D01*
X-867760Y-493100D01*
X-867200Y-493000D01*
X-866640Y-493100D01*
X-866150Y-493500D01*
X-865730Y-494100D01*
X-865450Y-494800D01*
X-865310Y-495600D01*
Y-496400D01*
X-865450Y-497200D01*
X-865730Y-497900D01*
X-866150Y-498500D01*
X-866640Y-498900D01*
X-867200Y-499000D01*
G01X-861500Y-493000D02*
Y-499000D01*
G01X-863110Y-493000D02*
X-859890D01*
G01X-856640D02*
X-854960D01*
G01X-855800D02*
Y-499000D01*
G01X-856640D02*
X-854960D01*
G01X-848560Y-493500D02*
X-848980Y-493200D01*
X-849470Y-493000D01*
X-850030D01*
X-850660Y-493300D01*
X-851150Y-493800D01*
X-851500Y-494400D01*
X-851780Y-495400D01*
X-851850Y-496300D01*
X-851710Y-497200D01*
X-851500Y-497800D01*
X-851080Y-498400D01*
X-850590Y-498800D01*
X-850100Y-499000D01*
X-849610D01*
X-849120Y-498800D01*
X-848700Y-498500D01*
X-848350Y-498100D01*
G01X-843000Y-499000D02*
X-845800D01*
Y-493000D01*
X-843000D01*
G01X-844120Y-495900D02*
X-845800D01*
G01X-833000Y-499000D02*
X-833560Y-498900D01*
X-834050Y-498500D01*
X-834470Y-497900D01*
X-834750Y-497200D01*
X-834890Y-496400D01*
Y-495600D01*
X-834750Y-494800D01*
X-834470Y-494100D01*
X-834050Y-493500D01*
X-833560Y-493100D01*
X-833000Y-493000D01*
X-832440Y-493100D01*
X-831950Y-493500D01*
X-831530Y-494100D01*
X-831250Y-494800D01*
X-831110Y-495600D01*
Y-496400D01*
X-831250Y-497200D01*
X-831530Y-497900D01*
X-831950Y-498500D01*
X-832440Y-498900D01*
X-833000Y-499000D01*
G01X-828630D02*
Y-493000D01*
X-825970D01*
G01X-826950Y-495900D02*
X-828630D01*
G01X-817300Y-499000D02*
Y-493000D01*
X-815620D01*
X-815060Y-493300D01*
X-814640Y-494000D01*
X-814500Y-494800D01*
X-814640Y-495600D01*
X-814990Y-496200D01*
X-815620Y-496500D01*
X-817300D01*
G01X-811600Y-499000D02*
Y-493000D01*
X-809850D01*
X-809290Y-493300D01*
X-808940Y-493700D01*
X-808800Y-494500D01*
X-808940Y-495300D01*
X-809360Y-495800D01*
X-809850Y-496100D01*
X-811600D01*
G01X-809850D02*
X-808800Y-499000D01*
G01X-804500D02*
X-805060Y-498900D01*
X-805550Y-498500D01*
X-805970Y-497900D01*
X-806250Y-497200D01*
X-806390Y-496400D01*
Y-495600D01*
X-806250Y-494800D01*
X-805970Y-494100D01*
X-805550Y-493500D01*
X-805060Y-493100D01*
X-804500Y-493000D01*
X-803940Y-493100D01*
X-803450Y-493500D01*
X-803030Y-494100D01*
X-802750Y-494800D01*
X-802610Y-495600D01*
Y-496400D01*
X-802750Y-497200D01*
X-803030Y-497900D01*
X-803450Y-498500D01*
X-803940Y-498900D01*
X-804500Y-499000D01*
G01X-800200D02*
Y-493000D01*
X-798520D01*
X-797960Y-493300D01*
X-797540Y-494000D01*
X-797400Y-494800D01*
X-797540Y-495600D01*
X-797890Y-496200D01*
X-798520Y-496500D01*
X-800200D01*
G01X-794500Y-499000D02*
Y-493000D01*
X-792750D01*
X-792190Y-493300D01*
X-791840Y-493700D01*
X-791700Y-494500D01*
X-791840Y-495300D01*
X-792260Y-495800D01*
X-792750Y-496100D01*
X-794500D01*
G01X-792750D02*
X-791700Y-499000D01*
G01X-788240Y-493000D02*
X-786560D01*
G01X-787400D02*
Y-499000D01*
G01X-788240D02*
X-786560D01*
G01X-780300D02*
X-783100D01*
Y-493000D01*
X-780300D01*
G01X-781420Y-495900D02*
X-783100D01*
G01X-776000Y-493000D02*
Y-499000D01*
G01X-777610Y-493000D02*
X-774390D01*
G01X-772050Y-499000D02*
X-770300Y-493000D01*
X-768550Y-499000D01*
G01X-769180Y-496900D02*
X-771420D01*
G01X-766000Y-499000D02*
Y-493000D01*
X-764250D01*
X-763690Y-493300D01*
X-763340Y-493700D01*
X-763200Y-494500D01*
X-763340Y-495300D01*
X-763760Y-495800D01*
X-764250Y-496100D01*
X-766000D01*
G01X-764250D02*
X-763200Y-499000D01*
G01X-758900D02*
Y-496300D01*
X-760300Y-493000D01*
G01X-757500D02*
X-758900Y-496300D01*
G01X-748900Y-499000D02*
Y-493000D01*
X-747220D01*
X-746660Y-493300D01*
X-746240Y-494000D01*
X-746100Y-494800D01*
X-746240Y-495600D01*
X-746590Y-496200D01*
X-747220Y-496500D01*
X-748900D01*
G01X-743200Y-499000D02*
Y-493000D01*
X-741450D01*
X-740890Y-493300D01*
X-740540Y-493700D01*
X-740400Y-494500D01*
X-740540Y-495300D01*
X-740960Y-495800D01*
X-741450Y-496100D01*
X-743200D01*
G01X-741450D02*
X-740400Y-499000D01*
G01X-736100D02*
X-736660Y-498900D01*
X-737150Y-498500D01*
X-737570Y-497900D01*
X-737850Y-497200D01*
X-737990Y-496400D01*
Y-495600D01*
X-737850Y-494800D01*
X-737570Y-494100D01*
X-737150Y-493500D01*
X-736660Y-493100D01*
X-736100Y-493000D01*
X-735540Y-493100D01*
X-735050Y-493500D01*
X-734630Y-494100D01*
X-734350Y-494800D01*
X-734210Y-495600D01*
Y-496400D01*
X-734350Y-497200D01*
X-734630Y-497900D01*
X-735050Y-498500D01*
X-735540Y-498900D01*
X-736100Y-499000D01*
G01X-731800D02*
Y-493000D01*
X-730120D01*
X-729560Y-493300D01*
X-729140Y-494000D01*
X-729000Y-494800D01*
X-729140Y-495600D01*
X-729490Y-496200D01*
X-730120Y-496500D01*
X-731800D01*
G01X-723300Y-499000D02*
X-726100D01*
Y-493000D01*
X-723300D01*
G01X-724420Y-495900D02*
X-726100D01*
G01X-720400Y-499000D02*
Y-493000D01*
X-718650D01*
X-718090Y-493300D01*
X-717740Y-493700D01*
X-717600Y-494500D01*
X-717740Y-495300D01*
X-718160Y-495800D01*
X-718650Y-496100D01*
X-720400D01*
G01X-718650D02*
X-717600Y-499000D01*
G01X-713300Y-493000D02*
Y-499000D01*
G01X-714910Y-493000D02*
X-711690D01*
G01X-707600Y-499000D02*
Y-496300D01*
X-709000Y-493000D01*
G01X-706200D02*
X-707600Y-496300D01*
G01X-701900Y-499200D02*
X-702040Y-499100D01*
Y-498900D01*
X-701900Y-498800D01*
X-701760Y-498900D01*
Y-499100D01*
X-701900Y-499200D01*
G01Y-496500D02*
X-702040Y-496400D01*
Y-496200D01*
X-701900Y-496100D01*
X-701760Y-496200D01*
Y-496400D01*
X-701900Y-496500D01*
G54D15*
X-145079Y-105312D03*
X-154921Y-50942D03*
Y1459D03*
X-127362Y-105312D03*
X-111614Y-50942D03*
Y1459D03*
X-101772Y-105312D03*
X-84055D03*
X-68307Y-50942D03*
Y1459D03*
G54D25*
G01X-1621600Y-69400D02*
X-1623900D01*
X-1625600Y-71100D01*
Y-81500D01*
X-1611600Y-95500D01*
Y-181950D01*
X-1610500Y-183050D01*
X-1605550D01*
X-1604100Y-181600D01*
Y-143864D01*
X-1600236Y-140000D01*
G01X-1592362Y-139606D02*
X-1592394D01*
X-1596000Y-136000D01*
Y-93700D01*
X-1597400Y-92300D01*
X-1604200D01*
X-1614900Y-81600D01*
Y-70800D01*
X-1618500Y-67200D01*
G01X-1618400Y-71600D02*
Y-84800D01*
X-1604600Y-98600D01*
Y-130124D01*
X-1600236Y-134488D01*
G01X-1530000Y-120300D02*
X-1537000Y-127300D01*
Y-141600D01*
X-1541300Y-145900D01*
Y-181200D01*
X-1542800Y-182700D01*
X-1578850D01*
X-1580500Y-181050D01*
Y-138500D01*
X-1584488Y-134512D01*
Y-134488D01*
G01Y-140000D02*
X-1584500D01*
X-1588500Y-136000D01*
Y-95000D01*
X-1575400Y-81900D01*
X-1513900D01*
X-1498400Y-66400D01*
X-1481900D01*
X-1478800Y-69500D01*
X-1464083D01*
X-1461693Y-71890D01*
G01X-1476693D02*
X-1478610D01*
X-1482700Y-67800D01*
X-1497000D01*
X-1513001Y-83801D01*
X-1565801D01*
X-1573100Y-91100D01*
Y-136092D01*
X-1576614Y-139606D01*
G01Y-145118D02*
Y-145014D01*
X-1572100Y-140500D01*
Y-94400D01*
X-1563650Y-85950D01*
X-1511650D01*
X-1500140Y-74440D01*
X-1490690D01*
X-1489600Y-73350D01*
Y-70600D01*
X-1488000Y-69000D01*
X-1484583D01*
X-1481693Y-71890D01*
G01X-1568740Y-134488D02*
X-1565200Y-130948D01*
Y-93200D01*
X-1559270Y-87270D01*
X-1508560D01*
X-1500580Y-79290D01*
X-1490490D01*
X-1489100Y-77900D01*
Y-76100D01*
X-1486890Y-73890D01*
X-1473890D01*
X-1471890Y-71890D01*
X-1471693D01*
G01X-1568740Y-140000D02*
X-1564200Y-135460D01*
Y-96000D01*
X-1557950Y-89750D01*
X-1507720D01*
X-1502290Y-84320D01*
X-1492820D01*
X-1487600Y-79100D01*
X-1485800D01*
X-1484200Y-77500D01*
Y-76500D01*
X-1482700Y-75000D01*
X-1468950D01*
X-1468000Y-74050D01*
Y-73197D01*
X-1466693Y-71890D01*
G01X-1476693Y-76890D02*
X-1479051Y-79248D01*
X-1478950Y-79350D01*
Y-87860D01*
X-1480040Y-88950D01*
X-1491930D01*
X-1495560Y-92580D01*
X-1554480D01*
X-1556400Y-94500D01*
Y-140652D01*
X-1560866Y-145118D01*
G01Y-139606D02*
X-1557400Y-136140D01*
Y-92900D01*
X-1555449Y-90949D01*
X-1503261D01*
X-1498552Y-86240D01*
X-1491043D01*
X-1489236Y-84433D01*
X-1486143D01*
X-1484460Y-82750D01*
Y-79657D01*
X-1481693Y-76890D01*
G01X-1552992Y-134488D02*
X-1549640Y-131136D01*
Y-97990D01*
X-1547350Y-95700D01*
X-1518390D01*
X-1514830Y-99260D01*
X-1475280D01*
X-1474000Y-97980D01*
Y-79197D01*
X-1471693Y-76890D01*
G01X-1466693D02*
X-1469210Y-79407D01*
Y-108080D01*
X-1470570Y-109440D01*
X-1490840D01*
X-1493590Y-106690D01*
X-1511370D01*
X-1520560Y-97500D01*
X-1546500D01*
X-1548500Y-99500D01*
Y-135500D01*
X-1552992Y-139992D01*
Y-140000D01*
G01X-1466693Y-81890D02*
X-1464000Y-84583D01*
Y-117500D01*
X-1466100Y-119600D01*
X-1524800D01*
X-1528400Y-116000D01*
X-1532700D01*
X-1541500Y-124800D01*
Y-135988D01*
X-1545118Y-139606D01*
G01Y-145118D02*
X-1539500Y-139500D01*
Y-125400D01*
X-1531350Y-117250D01*
X-1529000D01*
X-1524700Y-121550D01*
X-1493050D01*
X-1491280Y-123320D01*
Y-126140D01*
X-1488120Y-129300D01*
X-1459800D01*
X-1458800Y-128300D01*
Y-79783D01*
X-1461693Y-76890D01*
G01X-1202580Y-176300D02*
X-1205500D01*
X-1219370Y-190170D01*
X-1239310D01*
X-1240580Y-188900D01*
Y-183400D01*
X-1242500Y-181480D01*
X-1249031D01*
X-1250591Y-179920D01*
G01X-374800Y-105700D02*
Y-116130D01*
X-407500Y-148830D01*
Y-178500D01*
X-411500Y-182500D01*
X-607000D01*
X-615500Y-174000D01*
X-658500D01*
X-668300Y-183800D01*
X-714500D01*
X-718100Y-180200D01*
Y-143790D01*
X-722283Y-139606D01*
G01X-714409Y-140000D02*
X-714421D01*
X-718421Y-136000D01*
Y-95000D01*
X-705321Y-81900D01*
X-643821D01*
X-628321Y-66400D01*
X-611821D01*
X-608721Y-69500D01*
X-594004D01*
X-591614Y-71890D01*
G01X-649700Y-117200D02*
X-666100Y-133600D01*
Y-143700D01*
X-668600Y-146200D01*
Y-178679D01*
X-672021Y-182100D01*
X-709050D01*
X-710421Y-180729D01*
Y-138500D01*
X-714409Y-134512D01*
Y-134488D01*
G01X-606614Y-71890D02*
X-608532D01*
X-612621Y-67800D01*
X-626921D01*
X-642922Y-83801D01*
X-695722D01*
X-703021Y-91100D01*
Y-136092D01*
X-706535Y-139606D01*
G01Y-145118D02*
Y-145014D01*
X-702021Y-140500D01*
Y-94400D01*
X-693571Y-85950D01*
X-641571D01*
X-630061Y-74440D01*
X-620611D01*
X-619521Y-73350D01*
Y-70600D01*
X-617921Y-69000D01*
X-614504D01*
X-611614Y-71890D01*
G01X-698661Y-134488D02*
X-695121Y-130948D01*
Y-93200D01*
X-689191Y-87270D01*
X-638481D01*
X-630501Y-79290D01*
X-620411D01*
X-619021Y-77900D01*
Y-76100D01*
X-616791Y-73870D01*
X-603791D01*
X-601811Y-71890D01*
X-601614D01*
G01X-698661Y-140000D02*
X-694121Y-135460D01*
Y-96000D01*
X-687871Y-89750D01*
X-637641D01*
X-632211Y-84320D01*
X-622741D01*
X-617521Y-79100D01*
X-615721D01*
X-614121Y-77500D01*
Y-76500D01*
X-612621Y-75000D01*
X-598871D01*
X-597921Y-74050D01*
Y-73197D01*
X-596614Y-71890D01*
G01X-606614Y-76890D02*
X-608973Y-79248D01*
X-608871Y-79350D01*
Y-87860D01*
X-609961Y-88950D01*
X-621851D01*
X-625481Y-92580D01*
X-684401D01*
X-686321Y-94500D01*
Y-140652D01*
X-690787Y-145118D01*
G01Y-139606D02*
X-687321Y-136140D01*
Y-92900D01*
X-685370Y-90949D01*
X-633182D01*
X-628473Y-86240D01*
X-620964D01*
X-619158Y-84433D01*
X-616064D01*
X-614381Y-82750D01*
Y-79657D01*
X-611614Y-76890D01*
G01X-682913Y-134488D02*
X-679561Y-131136D01*
Y-97990D01*
X-677271Y-95700D01*
X-648311D01*
X-644751Y-99260D01*
X-605201D01*
X-603921Y-97980D01*
Y-79197D01*
X-601614Y-76890D01*
G01X-596614D02*
X-599131Y-79407D01*
Y-108080D01*
X-600491Y-109440D01*
X-620761D01*
X-623511Y-106690D01*
X-641291D01*
X-650481Y-97500D01*
X-676421D01*
X-678421Y-99500D01*
Y-135500D01*
X-682913Y-139992D01*
Y-140000D01*
G01X-675039Y-139606D02*
X-671421Y-135988D01*
Y-124800D01*
X-659711Y-113090D01*
X-634420D01*
X-627910Y-119600D01*
X-596021D01*
X-593921Y-117500D01*
Y-84583D01*
X-596614Y-81890D01*
G01X-591614Y-76890D02*
X-588721Y-79783D01*
Y-128300D01*
X-589721Y-129300D01*
X-625390D01*
X-639861Y-114829D01*
X-658850D01*
X-669421Y-125400D01*
Y-139500D01*
X-675039Y-145118D01*
G54D16*
X-145079Y-95824D03*
Y-80864D03*
Y-65903D03*
Y-50942D03*
X-136220Y-95824D03*
X-127362D03*
X-136220Y-80864D03*
X-127362D03*
X-136220Y-65903D03*
X-127362D03*
X-136220Y-50942D03*
X-127362D03*
X-101772Y-95824D03*
Y-80864D03*
Y-65903D03*
Y-50942D03*
X-92913Y-95824D03*
X-84055D03*
X-92913Y-80864D03*
X-84055D03*
X-92913Y-65903D03*
X-84055D03*
X-92913Y-50942D03*
X-84055D03*
G54D26*
G01X-1189333Y-572500D02*
Y-565500D01*
X-1187667D01*
X-1187000Y-565850D01*
X-1186500Y-566317D01*
X-1186083Y-567017D01*
X-1185750Y-567833D01*
X-1185667Y-569000D01*
X-1185750Y-570167D01*
X-1186083Y-570983D01*
X-1186500Y-571684D01*
X-1187000Y-572150D01*
X-1187667Y-572500D01*
X-1189333D01*
G01X-1180700D02*
X-1181367Y-572383D01*
X-1181950Y-571917D01*
X-1182450Y-571217D01*
X-1182783Y-570400D01*
X-1182950Y-569467D01*
Y-568533D01*
X-1182783Y-567600D01*
X-1182450Y-566783D01*
X-1181950Y-566083D01*
X-1181367Y-565617D01*
X-1180700Y-565500D01*
X-1180033Y-565617D01*
X-1179450Y-566083D01*
X-1178950Y-566783D01*
X-1178617Y-567600D01*
X-1178450Y-568533D01*
Y-569467D01*
X-1178617Y-570400D01*
X-1178950Y-571217D01*
X-1179450Y-571917D01*
X-1180033Y-572383D01*
X-1180700Y-572500D01*
G01X-1172067Y-566083D02*
X-1172567Y-565733D01*
X-1173150Y-565500D01*
X-1173817D01*
X-1174567Y-565850D01*
X-1175150Y-566433D01*
X-1175567Y-567133D01*
X-1175900Y-568300D01*
X-1175983Y-569350D01*
X-1175817Y-570400D01*
X-1175567Y-571100D01*
X-1175067Y-571800D01*
X-1174483Y-572267D01*
X-1173900Y-572500D01*
X-1173317D01*
X-1172733Y-572267D01*
X-1172233Y-571917D01*
X-1171817Y-571450D01*
G01X-1168933Y-565500D02*
Y-570517D01*
X-1168600Y-571567D01*
X-1167933Y-572267D01*
X-1167100Y-572500D01*
X-1166267Y-572267D01*
X-1165600Y-571567D01*
X-1165267Y-570517D01*
Y-565500D01*
G01X-1162467Y-572500D02*
Y-565500D01*
X-1160300Y-571333D01*
X-1158133Y-565500D01*
Y-572500D01*
G01X-1151833D02*
X-1155167D01*
Y-565500D01*
X-1151833D01*
G01X-1153167Y-568883D02*
X-1155167D01*
G01X-1148617Y-572500D02*
Y-565500D01*
X-1144783Y-572500D01*
Y-565500D01*
G01X-1139900D02*
Y-572500D01*
G01X-1141817Y-565500D02*
X-1137983D01*
G01X-1128217Y-572500D02*
Y-565500D01*
X-1124383Y-572500D01*
Y-565500D01*
G01X-1121333D02*
Y-570517D01*
X-1121000Y-571567D01*
X-1120333Y-572267D01*
X-1119500Y-572500D01*
X-1118667Y-572267D01*
X-1118000Y-571567D01*
X-1117667Y-570517D01*
Y-565500D01*
G01X-1114867Y-572500D02*
Y-565500D01*
X-1112700Y-571333D01*
X-1110533Y-565500D01*
Y-572500D01*
G01X-1105233Y-568767D02*
X-1104900Y-568417D01*
X-1104650Y-567833D01*
X-1104483Y-567017D01*
X-1104650Y-566317D01*
X-1104983Y-565850D01*
X-1105567Y-565500D01*
X-1107817D01*
Y-572500D01*
X-1105067D01*
X-1104483Y-572033D01*
X-1104150Y-571333D01*
X-1103983Y-570517D01*
X-1104150Y-569700D01*
X-1104650Y-569000D01*
X-1105233Y-568767D01*
X-1107817D01*
G01X-1097433Y-572500D02*
X-1100767D01*
Y-565500D01*
X-1097433D01*
G01X-1098767Y-568883D02*
X-1100767D01*
G01X-1093967Y-572500D02*
Y-565500D01*
X-1091883D01*
X-1091217Y-565850D01*
X-1090800Y-566317D01*
X-1090633Y-567250D01*
X-1090800Y-568183D01*
X-1091300Y-568767D01*
X-1091883Y-569117D01*
X-1093967D01*
G01X-1091883D02*
X-1090633Y-572500D01*
G01X-1189250Y-531567D02*
X-1188583Y-532150D01*
X-1187833Y-532500D01*
X-1187167D01*
X-1186500Y-532150D01*
X-1186000Y-531567D01*
X-1185750Y-530750D01*
X-1185917Y-529933D01*
X-1186333Y-529233D01*
X-1187083Y-528767D01*
X-1188083Y-528533D01*
X-1188667Y-528067D01*
X-1188917Y-527250D01*
X-1188750Y-526433D01*
X-1188333Y-525850D01*
X-1187750Y-525500D01*
X-1187167D01*
X-1186583Y-525733D01*
X-1186083Y-526317D01*
G01X-1182450Y-532500D02*
Y-525500D01*
G01X-1178950D02*
Y-532500D01*
G01Y-529000D02*
X-1182450D01*
G01X-1172233Y-532500D02*
X-1175567D01*
Y-525500D01*
X-1172233D01*
G01X-1173567Y-528883D02*
X-1175567D01*
G01X-1165433Y-532500D02*
X-1168767D01*
Y-525500D01*
X-1165433D01*
G01X-1166767Y-528883D02*
X-1168767D01*
G01X-1160300Y-525500D02*
Y-532500D01*
G01X-1162217Y-525500D02*
X-1158383D01*
G01X-1146700D02*
Y-532500D01*
G01X-1148617Y-525500D02*
X-1144783D01*
G01X-1140900D02*
X-1138900D01*
G01X-1139900D02*
Y-532500D01*
G01X-1140900D02*
X-1138900D01*
G01X-1133100Y-525500D02*
Y-532500D01*
G01X-1135017Y-525500D02*
X-1131183D01*
G01X-1127967D02*
Y-532500D01*
X-1124633D01*
G01X-1117833D02*
X-1121167D01*
Y-525500D01*
X-1117833D01*
G01X-1119167Y-528883D02*
X-1121167D01*
G01X-1112700Y-532733D02*
X-1112867Y-532617D01*
Y-532383D01*
X-1112700Y-532267D01*
X-1112533Y-532383D01*
Y-532617D01*
X-1112700Y-532733D01*
G01Y-529584D02*
X-1112867Y-529467D01*
Y-529233D01*
X-1112700Y-529117D01*
X-1112533Y-529233D01*
Y-529467D01*
X-1112700Y-529584D01*
G01X-1187500Y-485500D02*
Y-492500D01*
G01X-1189417Y-485500D02*
X-1185583D01*
G01X-1181700D02*
X-1179700D01*
G01X-1180700D02*
Y-492500D01*
G01X-1181700D02*
X-1179700D01*
G01X-1173900Y-485500D02*
Y-492500D01*
G01X-1175817Y-485500D02*
X-1171983D01*
G01X-1168767D02*
Y-492500D01*
X-1165433D01*
G01X-1158633D02*
X-1161967D01*
Y-485500D01*
X-1158633D01*
G01X-1159967Y-488883D02*
X-1161967D01*
G01X-916667Y-570000D02*
Y-563000D01*
X-914583D01*
X-913917Y-563350D01*
X-913500Y-563817D01*
X-913333Y-564750D01*
X-913500Y-565683D01*
X-914000Y-566267D01*
X-914583Y-566617D01*
X-916667D01*
G01X-914583D02*
X-913333Y-570000D01*
G01X-906533D02*
X-909867D01*
Y-563000D01*
X-906533D01*
G01X-907867Y-566383D02*
X-909867D01*
G01X-903483Y-563000D02*
X-901400Y-570000D01*
X-899317Y-563000D01*
G01X-907850Y-451567D02*
X-907183Y-452150D01*
X-906433Y-452500D01*
X-905767D01*
X-905100Y-452150D01*
X-904600Y-451567D01*
X-904350Y-450750D01*
X-904517Y-449933D01*
X-904933Y-449233D01*
X-905683Y-448767D01*
X-906683Y-448533D01*
X-907267Y-448067D01*
X-907517Y-447250D01*
X-907350Y-446433D01*
X-906933Y-445850D01*
X-906350Y-445500D01*
X-905767D01*
X-905183Y-445733D01*
X-904683Y-446317D01*
G01X-897467Y-446083D02*
X-897967Y-445733D01*
X-898550Y-445500D01*
X-899217D01*
X-899967Y-445850D01*
X-900550Y-446433D01*
X-900967Y-447133D01*
X-901300Y-448300D01*
X-901383Y-449350D01*
X-901217Y-450400D01*
X-900967Y-451100D01*
X-900467Y-451800D01*
X-899883Y-452267D01*
X-899300Y-452500D01*
X-898717D01*
X-898133Y-452267D01*
X-897633Y-451917D01*
X-897217Y-451450D01*
G01X-894583Y-452500D02*
X-892500Y-445500D01*
X-890417Y-452500D01*
G01X-891167Y-450050D02*
X-893833D01*
G01X-887367Y-445500D02*
Y-452500D01*
X-884033D01*
G01X-877233D02*
X-880567D01*
Y-445500D01*
X-877233D01*
G01X-878567Y-448883D02*
X-880567D01*
G01X-874333Y-572500D02*
Y-565500D01*
X-872667D01*
X-872000Y-565850D01*
X-871500Y-566317D01*
X-871083Y-567017D01*
X-870750Y-567833D01*
X-870667Y-569000D01*
X-870750Y-570167D01*
X-871083Y-570983D01*
X-871500Y-571684D01*
X-872000Y-572150D01*
X-872667Y-572500D01*
X-874333D01*
G01X-866700Y-565500D02*
X-864700D01*
G01X-865700D02*
Y-572500D01*
G01X-866700D02*
X-864700D01*
G01X-860650Y-571567D02*
X-859983Y-572150D01*
X-859233Y-572500D01*
X-858567D01*
X-857900Y-572150D01*
X-857400Y-571567D01*
X-857150Y-570750D01*
X-857317Y-569933D01*
X-857733Y-569233D01*
X-858483Y-568767D01*
X-859483Y-568533D01*
X-860067Y-568067D01*
X-860317Y-567250D01*
X-860150Y-566433D01*
X-859733Y-565850D01*
X-859150Y-565500D01*
X-858567D01*
X-857983Y-565733D01*
X-857483Y-566317D01*
G01X-850267Y-566083D02*
X-850767Y-565733D01*
X-851350Y-565500D01*
X-852017D01*
X-852767Y-565850D01*
X-853350Y-566433D01*
X-853767Y-567133D01*
X-854100Y-568300D01*
X-854183Y-569350D01*
X-854017Y-570400D01*
X-853767Y-571100D01*
X-853267Y-571800D01*
X-852683Y-572267D01*
X-852100Y-572500D01*
X-851517D01*
X-850933Y-572267D01*
X-850433Y-571917D01*
X-850017Y-571450D01*
G01X-846967Y-565500D02*
Y-572500D01*
X-843633D01*
G01X-838500D02*
X-839167Y-572383D01*
X-839750Y-571917D01*
X-840250Y-571217D01*
X-840583Y-570400D01*
X-840750Y-569467D01*
Y-568533D01*
X-840583Y-567600D01*
X-840250Y-566783D01*
X-839750Y-566083D01*
X-839167Y-565617D01*
X-838500Y-565500D01*
X-837833Y-565617D01*
X-837250Y-566083D01*
X-836750Y-566783D01*
X-836417Y-567600D01*
X-836250Y-568533D01*
Y-569467D01*
X-836417Y-570400D01*
X-836750Y-571217D01*
X-837250Y-571917D01*
X-837833Y-572383D01*
X-838500Y-572500D01*
G01X-833450Y-571567D02*
X-832783Y-572150D01*
X-832033Y-572500D01*
X-831367D01*
X-830700Y-572150D01*
X-830200Y-571567D01*
X-829950Y-570750D01*
X-830117Y-569933D01*
X-830533Y-569233D01*
X-831283Y-568767D01*
X-832283Y-568533D01*
X-832867Y-568067D01*
X-833117Y-567250D01*
X-832950Y-566433D01*
X-832533Y-565850D01*
X-831950Y-565500D01*
X-831367D01*
X-830783Y-565733D01*
X-830283Y-566317D01*
G01X-823233Y-572500D02*
X-826567D01*
Y-565500D01*
X-823233D01*
G01X-824567Y-568883D02*
X-826567D01*
G01X-819933Y-572500D02*
Y-565500D01*
X-818267D01*
X-817600Y-565850D01*
X-817100Y-566317D01*
X-816683Y-567017D01*
X-816350Y-567833D01*
X-816267Y-569000D01*
X-816350Y-570167D01*
X-816683Y-570983D01*
X-817100Y-571684D01*
X-817600Y-572150D01*
X-818267Y-572500D01*
X-819933D01*
G01X-807000Y-565500D02*
X-805833Y-572500D01*
X-804500Y-565500D01*
X-803167Y-572500D01*
X-802000Y-565500D01*
G01X-798700D02*
X-796700D01*
G01X-797700D02*
Y-572500D01*
G01X-798700D02*
X-796700D01*
G01X-790900Y-565500D02*
Y-572500D01*
G01X-792817Y-565500D02*
X-788983D01*
G01X-785850Y-572500D02*
Y-565500D01*
G01X-782350D02*
Y-572500D01*
G01Y-569000D02*
X-785850D01*
G01X-777300Y-572500D02*
X-777967Y-572383D01*
X-778550Y-571917D01*
X-779050Y-571217D01*
X-779383Y-570400D01*
X-779550Y-569467D01*
Y-568533D01*
X-779383Y-567600D01*
X-779050Y-566783D01*
X-778550Y-566083D01*
X-777967Y-565617D01*
X-777300Y-565500D01*
X-776633Y-565617D01*
X-776050Y-566083D01*
X-775550Y-566783D01*
X-775217Y-567600D01*
X-775050Y-568533D01*
Y-569467D01*
X-775217Y-570400D01*
X-775550Y-571217D01*
X-776050Y-571917D01*
X-776633Y-572383D01*
X-777300Y-572500D01*
G01X-772333Y-565500D02*
Y-570517D01*
X-772000Y-571567D01*
X-771333Y-572267D01*
X-770500Y-572500D01*
X-769667Y-572267D01*
X-769000Y-571567D01*
X-768667Y-570517D01*
Y-565500D01*
G01X-763700D02*
Y-572500D01*
G01X-765617Y-565500D02*
X-761783D01*
G01X-750100D02*
Y-572500D01*
G01X-752017Y-565500D02*
X-748183D01*
G01X-745050Y-572500D02*
Y-565500D01*
G01X-741550D02*
Y-572500D01*
G01Y-569000D02*
X-745050D01*
G01X-734833Y-572500D02*
X-738167D01*
Y-565500D01*
X-734833D01*
G01X-736167Y-568883D02*
X-738167D01*
G01X-724567Y-572500D02*
Y-565500D01*
X-722567D01*
X-721900Y-565850D01*
X-721400Y-566667D01*
X-721233Y-567600D01*
X-721400Y-568533D01*
X-721817Y-569233D01*
X-722567Y-569584D01*
X-724567D01*
G01X-717767Y-572500D02*
Y-565500D01*
X-715683D01*
X-715017Y-565850D01*
X-714600Y-566317D01*
X-714433Y-567250D01*
X-714600Y-568183D01*
X-715100Y-568767D01*
X-715683Y-569117D01*
X-717767D01*
G01X-715683D02*
X-714433Y-572500D01*
G01X-710300Y-565500D02*
X-708300D01*
G01X-709300D02*
Y-572500D01*
G01X-710300D02*
X-708300D01*
G01X-702500D02*
X-703167Y-572383D01*
X-703750Y-571917D01*
X-704250Y-571217D01*
X-704583Y-570400D01*
X-704750Y-569467D01*
Y-568533D01*
X-704583Y-567600D01*
X-704250Y-566783D01*
X-703750Y-566083D01*
X-703167Y-565617D01*
X-702500Y-565500D01*
X-701833Y-565617D01*
X-701250Y-566083D01*
X-700750Y-566783D01*
X-700417Y-567600D01*
X-700250Y-568533D01*
Y-569467D01*
X-700417Y-570400D01*
X-700750Y-571217D01*
X-701250Y-571917D01*
X-701833Y-572383D01*
X-702500Y-572500D01*
G01X-697367D02*
Y-565500D01*
X-695283D01*
X-694617Y-565850D01*
X-694200Y-566317D01*
X-694033Y-567250D01*
X-694200Y-568183D01*
X-694700Y-568767D01*
X-695283Y-569117D01*
X-697367D01*
G01X-695283D02*
X-694033Y-572500D01*
G01X-684600Y-565500D02*
X-683433Y-572500D01*
X-682100Y-565500D01*
X-680767Y-572500D01*
X-679600Y-565500D01*
G01X-676967Y-572500D02*
Y-565500D01*
X-674883D01*
X-674217Y-565850D01*
X-673800Y-566317D01*
X-673633Y-567250D01*
X-673800Y-568183D01*
X-674300Y-568767D01*
X-674883Y-569117D01*
X-676967D01*
G01X-674883D02*
X-673633Y-572500D01*
G01X-669500Y-565500D02*
X-667500D01*
G01X-668500D02*
Y-572500D01*
G01X-669500D02*
X-667500D01*
G01X-661700Y-565500D02*
Y-572500D01*
G01X-663617Y-565500D02*
X-659783D01*
G01X-654900D02*
Y-572500D01*
G01X-656817Y-565500D02*
X-652983D01*
G01X-646433Y-572500D02*
X-649767D01*
Y-565500D01*
X-646433D01*
G01X-647767Y-568883D02*
X-649767D01*
G01X-643217Y-572500D02*
Y-565500D01*
X-639383Y-572500D01*
Y-565500D01*
G01X-625867Y-566083D02*
X-626367Y-565733D01*
X-626950Y-565500D01*
X-627617D01*
X-628367Y-565850D01*
X-628950Y-566433D01*
X-629367Y-567133D01*
X-629700Y-568300D01*
X-629783Y-569350D01*
X-629617Y-570400D01*
X-629367Y-571100D01*
X-628867Y-571800D01*
X-628283Y-572267D01*
X-627700Y-572500D01*
X-627117D01*
X-626533Y-572267D01*
X-626033Y-571917D01*
X-625617Y-571450D01*
G01X-620900Y-572500D02*
X-621567Y-572383D01*
X-622150Y-571917D01*
X-622650Y-571217D01*
X-622983Y-570400D01*
X-623150Y-569467D01*
Y-568533D01*
X-622983Y-567600D01*
X-622650Y-566783D01*
X-622150Y-566083D01*
X-621567Y-565617D01*
X-620900Y-565500D01*
X-620233Y-565617D01*
X-619650Y-566083D01*
X-619150Y-566783D01*
X-618817Y-567600D01*
X-618650Y-568533D01*
Y-569467D01*
X-618817Y-570400D01*
X-619150Y-571217D01*
X-619650Y-571917D01*
X-620233Y-572383D01*
X-620900Y-572500D01*
G01X-616017D02*
Y-565500D01*
X-612183Y-572500D01*
Y-565500D01*
G01X-609050Y-571567D02*
X-608383Y-572150D01*
X-607633Y-572500D01*
X-606967D01*
X-606300Y-572150D01*
X-605800Y-571567D01*
X-605550Y-570750D01*
X-605717Y-569933D01*
X-606133Y-569233D01*
X-606883Y-568767D01*
X-607883Y-568533D01*
X-608467Y-568067D01*
X-608717Y-567250D01*
X-608550Y-566433D01*
X-608133Y-565850D01*
X-607550Y-565500D01*
X-606967D01*
X-606383Y-565733D01*
X-605883Y-566317D01*
G01X-598833Y-572500D02*
X-602167D01*
Y-565500D01*
X-598833D01*
G01X-600167Y-568883D02*
X-602167D01*
G01X-595617Y-572500D02*
Y-565500D01*
X-591783Y-572500D01*
Y-565500D01*
G01X-586900D02*
Y-572500D01*
G01X-588817Y-565500D02*
X-584983D01*
G01X-872500Y-587500D02*
X-873167Y-587383D01*
X-873750Y-586917D01*
X-874250Y-586217D01*
X-874583Y-585400D01*
X-874750Y-584467D01*
Y-583533D01*
X-874583Y-582600D01*
X-874250Y-581783D01*
X-873750Y-581083D01*
X-873167Y-580617D01*
X-872500Y-580500D01*
X-871833Y-580617D01*
X-871250Y-581083D01*
X-870750Y-581783D01*
X-870417Y-582600D01*
X-870250Y-583533D01*
Y-584467D01*
X-870417Y-585400D01*
X-870750Y-586217D01*
X-871250Y-586917D01*
X-871833Y-587383D01*
X-872500Y-587500D01*
G01X-867283D02*
Y-580500D01*
X-864117D01*
G01X-865283Y-583883D02*
X-867283D01*
G01X-854267Y-587500D02*
Y-580500D01*
X-852100Y-586333D01*
X-849933Y-580500D01*
Y-587500D01*
G01X-846300Y-580500D02*
X-844300D01*
G01X-845300D02*
Y-587500D01*
G01X-846300D02*
X-844300D01*
G01X-836667Y-581083D02*
X-837167Y-580733D01*
X-837750Y-580500D01*
X-838417D01*
X-839167Y-580850D01*
X-839750Y-581433D01*
X-840167Y-582133D01*
X-840500Y-583300D01*
X-840583Y-584350D01*
X-840417Y-585400D01*
X-840167Y-586100D01*
X-839667Y-586800D01*
X-839083Y-587267D01*
X-838500Y-587500D01*
X-837917D01*
X-837333Y-587267D01*
X-836833Y-586917D01*
X-836417Y-586450D01*
G01X-833367Y-587500D02*
Y-580500D01*
X-831283D01*
X-830617Y-580850D01*
X-830200Y-581317D01*
X-830033Y-582250D01*
X-830200Y-583183D01*
X-830700Y-583767D01*
X-831283Y-584117D01*
X-833367D01*
G01X-831283D02*
X-830033Y-587500D01*
G01X-824900D02*
X-825567Y-587383D01*
X-826150Y-586917D01*
X-826650Y-586217D01*
X-826983Y-585400D01*
X-827150Y-584467D01*
Y-583533D01*
X-826983Y-582600D01*
X-826650Y-581783D01*
X-826150Y-581083D01*
X-825567Y-580617D01*
X-824900Y-580500D01*
X-824233Y-580617D01*
X-823650Y-581083D01*
X-823150Y-581783D01*
X-822817Y-582600D01*
X-822650Y-583533D01*
Y-584467D01*
X-822817Y-585400D01*
X-823150Y-586217D01*
X-823650Y-586917D01*
X-824233Y-587383D01*
X-824900Y-587500D01*
G01X-819850Y-586567D02*
X-819183Y-587150D01*
X-818433Y-587500D01*
X-817767D01*
X-817100Y-587150D01*
X-816600Y-586567D01*
X-816350Y-585750D01*
X-816517Y-584933D01*
X-816933Y-584233D01*
X-817683Y-583767D01*
X-818683Y-583533D01*
X-819267Y-583067D01*
X-819517Y-582250D01*
X-819350Y-581433D01*
X-818933Y-580850D01*
X-818350Y-580500D01*
X-817767D01*
X-817183Y-580733D01*
X-816683Y-581317D01*
G01X-811300Y-587500D02*
X-811967Y-587383D01*
X-812550Y-586917D01*
X-813050Y-586217D01*
X-813383Y-585400D01*
X-813550Y-584467D01*
Y-583533D01*
X-813383Y-582600D01*
X-813050Y-581783D01*
X-812550Y-581083D01*
X-811967Y-580617D01*
X-811300Y-580500D01*
X-810633Y-580617D01*
X-810050Y-581083D01*
X-809550Y-581783D01*
X-809217Y-582600D01*
X-809050Y-583533D01*
Y-584467D01*
X-809217Y-585400D01*
X-809550Y-586217D01*
X-810050Y-586917D01*
X-810633Y-587383D01*
X-811300Y-587500D01*
G01X-806083D02*
Y-580500D01*
X-802917D01*
G01X-804083Y-583883D02*
X-806083D01*
G01X-797700Y-580500D02*
Y-587500D01*
G01X-799617Y-580500D02*
X-795783D01*
G01X-782267Y-581083D02*
X-782767Y-580733D01*
X-783350Y-580500D01*
X-784017D01*
X-784767Y-580850D01*
X-785350Y-581433D01*
X-785767Y-582133D01*
X-786100Y-583300D01*
X-786183Y-584350D01*
X-786017Y-585400D01*
X-785767Y-586100D01*
X-785267Y-586800D01*
X-784683Y-587267D01*
X-784100Y-587500D01*
X-783517D01*
X-782933Y-587267D01*
X-782433Y-586917D01*
X-782017Y-586450D01*
G01X-777300Y-587500D02*
X-777967Y-587383D01*
X-778550Y-586917D01*
X-779050Y-586217D01*
X-779383Y-585400D01*
X-779550Y-584467D01*
Y-583533D01*
X-779383Y-582600D01*
X-779050Y-581783D01*
X-778550Y-581083D01*
X-777967Y-580617D01*
X-777300Y-580500D01*
X-776633Y-580617D01*
X-776050Y-581083D01*
X-775550Y-581783D01*
X-775217Y-582600D01*
X-775050Y-583533D01*
Y-584467D01*
X-775217Y-585400D01*
X-775550Y-586217D01*
X-776050Y-586917D01*
X-776633Y-587383D01*
X-777300Y-587500D01*
G01X-772167D02*
Y-580500D01*
X-770083D01*
X-769417Y-580850D01*
X-769000Y-581317D01*
X-768833Y-582250D01*
X-769000Y-583183D01*
X-769500Y-583767D01*
X-770083Y-584117D01*
X-772167D01*
G01X-770083D02*
X-768833Y-587500D01*
G01X-765367D02*
Y-580500D01*
X-763367D01*
X-762700Y-580850D01*
X-762200Y-581667D01*
X-762033Y-582600D01*
X-762200Y-583533D01*
X-762617Y-584233D01*
X-763367Y-584584D01*
X-765367D01*
G01X-756900Y-587500D02*
X-757567Y-587383D01*
X-758150Y-586917D01*
X-758650Y-586217D01*
X-758983Y-585400D01*
X-759150Y-584467D01*
Y-583533D01*
X-758983Y-582600D01*
X-758650Y-581783D01*
X-758150Y-581083D01*
X-757567Y-580617D01*
X-756900Y-580500D01*
X-756233Y-580617D01*
X-755650Y-581083D01*
X-755150Y-581783D01*
X-754817Y-582600D01*
X-754650Y-583533D01*
Y-584467D01*
X-754817Y-585400D01*
X-755150Y-586217D01*
X-755650Y-586917D01*
X-756233Y-587383D01*
X-756900Y-587500D01*
G01X-751767D02*
Y-580500D01*
X-749683D01*
X-749017Y-580850D01*
X-748600Y-581317D01*
X-748433Y-582250D01*
X-748600Y-583183D01*
X-749100Y-583767D01*
X-749683Y-584117D01*
X-751767D01*
G01X-749683D02*
X-748433Y-587500D01*
G01X-745383D02*
X-743300Y-580500D01*
X-741217Y-587500D01*
G01X-741967Y-585050D02*
X-744633D01*
G01X-736500Y-580500D02*
Y-587500D01*
G01X-738417Y-580500D02*
X-734583D01*
G01X-730700D02*
X-728700D01*
G01X-729700D02*
Y-587500D01*
G01X-730700D02*
X-728700D01*
G01X-722900D02*
X-723567Y-587383D01*
X-724150Y-586917D01*
X-724650Y-586217D01*
X-724983Y-585400D01*
X-725150Y-584467D01*
Y-583533D01*
X-724983Y-582600D01*
X-724650Y-581783D01*
X-724150Y-581083D01*
X-723567Y-580617D01*
X-722900Y-580500D01*
X-722233Y-580617D01*
X-721650Y-581083D01*
X-721150Y-581783D01*
X-720817Y-582600D01*
X-720650Y-583533D01*
Y-584467D01*
X-720817Y-585400D01*
X-721150Y-586217D01*
X-721650Y-586917D01*
X-722233Y-587383D01*
X-722900Y-587500D01*
G01X-718017D02*
Y-580500D01*
X-714183Y-587500D01*
Y-580500D01*
G01X-709300Y-587733D02*
X-709467Y-587617D01*
Y-587383D01*
X-709300Y-587267D01*
X-709133Y-587383D01*
Y-587617D01*
X-709300Y-587733D01*
G01X-870667Y-551083D02*
X-871167Y-550733D01*
X-871750Y-550500D01*
X-872417D01*
X-873167Y-550850D01*
X-873750Y-551433D01*
X-874167Y-552133D01*
X-874500Y-553300D01*
X-874583Y-554350D01*
X-874417Y-555400D01*
X-874167Y-556100D01*
X-873667Y-556800D01*
X-873083Y-557267D01*
X-872500Y-557500D01*
X-871917D01*
X-871333Y-557267D01*
X-870833Y-556917D01*
X-870417Y-556450D01*
G01X-865700Y-557500D02*
X-866367Y-557383D01*
X-866950Y-556917D01*
X-867450Y-556217D01*
X-867783Y-555400D01*
X-867950Y-554467D01*
Y-553533D01*
X-867783Y-552600D01*
X-867450Y-551783D01*
X-866950Y-551083D01*
X-866367Y-550617D01*
X-865700Y-550500D01*
X-865033Y-550617D01*
X-864450Y-551083D01*
X-863950Y-551783D01*
X-863617Y-552600D01*
X-863450Y-553533D01*
Y-554467D01*
X-863617Y-555400D01*
X-863950Y-556217D01*
X-864450Y-556917D01*
X-865033Y-557383D01*
X-865700Y-557500D01*
G01X-860817D02*
Y-550500D01*
X-856983Y-557500D01*
Y-550500D01*
G01X-853683Y-557500D02*
Y-550500D01*
X-850517D01*
G01X-851683Y-553883D02*
X-853683D01*
G01X-846300Y-550500D02*
X-844300D01*
G01X-845300D02*
Y-557500D01*
G01X-846300D02*
X-844300D01*
G01X-840333D02*
Y-550500D01*
X-838667D01*
X-838000Y-550850D01*
X-837500Y-551317D01*
X-837083Y-552017D01*
X-836750Y-552833D01*
X-836667Y-554000D01*
X-836750Y-555167D01*
X-837083Y-555983D01*
X-837500Y-556684D01*
X-838000Y-557150D01*
X-838667Y-557500D01*
X-840333D01*
G01X-830033D02*
X-833367D01*
Y-550500D01*
X-830033D01*
G01X-831367Y-553883D02*
X-833367D01*
G01X-826817Y-557500D02*
Y-550500D01*
X-822983Y-557500D01*
Y-550500D01*
G01X-816267Y-551083D02*
X-816767Y-550733D01*
X-817350Y-550500D01*
X-818017D01*
X-818767Y-550850D01*
X-819350Y-551433D01*
X-819767Y-552133D01*
X-820100Y-553300D01*
X-820183Y-554350D01*
X-820017Y-555400D01*
X-819767Y-556100D01*
X-819267Y-556800D01*
X-818683Y-557267D01*
X-818100Y-557500D01*
X-817517D01*
X-816933Y-557267D01*
X-816433Y-556917D01*
X-816017Y-556450D01*
G01X-809633Y-557500D02*
X-812967D01*
Y-550500D01*
X-809633D01*
G01X-810967Y-553883D02*
X-812967D01*
G01X-799783Y-557500D02*
X-797700Y-550500D01*
X-795617Y-557500D01*
G01X-796367Y-555050D02*
X-799033D01*
G01X-792817Y-557500D02*
Y-550500D01*
X-788983Y-557500D01*
Y-550500D01*
G01X-785933Y-557500D02*
Y-550500D01*
X-784267D01*
X-783600Y-550850D01*
X-783100Y-551317D01*
X-782683Y-552017D01*
X-782350Y-552833D01*
X-782267Y-554000D01*
X-782350Y-555167D01*
X-782683Y-555983D01*
X-783100Y-556684D01*
X-783600Y-557150D01*
X-784267Y-557500D01*
X-785933D01*
G01X-771500Y-550500D02*
X-769500D01*
G01X-770500D02*
Y-557500D01*
G01X-771500D02*
X-769500D01*
G01X-763700Y-550500D02*
Y-557500D01*
G01X-765617Y-550500D02*
X-761783D01*
G01X-758650Y-556567D02*
X-757983Y-557150D01*
X-757233Y-557500D01*
X-756567D01*
X-755900Y-557150D01*
X-755400Y-556567D01*
X-755150Y-555750D01*
X-755317Y-554933D01*
X-755733Y-554233D01*
X-756483Y-553767D01*
X-757483Y-553533D01*
X-758067Y-553067D01*
X-758317Y-552250D01*
X-758150Y-551433D01*
X-757733Y-550850D01*
X-757150Y-550500D01*
X-756567D01*
X-755983Y-550733D01*
X-755483Y-551317D01*
G01X-741467Y-551083D02*
X-741967Y-550733D01*
X-742550Y-550500D01*
X-743217D01*
X-743967Y-550850D01*
X-744550Y-551433D01*
X-744967Y-552133D01*
X-745300Y-553300D01*
X-745383Y-554350D01*
X-745217Y-555400D01*
X-744967Y-556100D01*
X-744467Y-556800D01*
X-743883Y-557267D01*
X-743300Y-557500D01*
X-742717D01*
X-742133Y-557267D01*
X-741633Y-556917D01*
X-741217Y-556450D01*
G01X-736500Y-557500D02*
X-737167Y-557383D01*
X-737750Y-556917D01*
X-738250Y-556217D01*
X-738583Y-555400D01*
X-738750Y-554467D01*
Y-553533D01*
X-738583Y-552600D01*
X-738250Y-551783D01*
X-737750Y-551083D01*
X-737167Y-550617D01*
X-736500Y-550500D01*
X-735833Y-550617D01*
X-735250Y-551083D01*
X-734750Y-551783D01*
X-734417Y-552600D01*
X-734250Y-553533D01*
Y-554467D01*
X-734417Y-555400D01*
X-734750Y-556217D01*
X-735250Y-556917D01*
X-735833Y-557383D01*
X-736500Y-557500D01*
G01X-731617D02*
Y-550500D01*
X-727783Y-557500D01*
Y-550500D01*
G01X-722900D02*
Y-557500D01*
G01X-724817Y-550500D02*
X-720983D01*
G01X-714433Y-557500D02*
X-717767D01*
Y-550500D01*
X-714433D01*
G01X-715767Y-553883D02*
X-717767D01*
G01X-711217Y-557500D02*
Y-550500D01*
X-707383Y-557500D01*
Y-550500D01*
G01X-702500D02*
Y-557500D01*
G01X-704417Y-550500D02*
X-700583D01*
G01X-697450Y-556567D02*
X-696783Y-557150D01*
X-696033Y-557500D01*
X-695367D01*
X-694700Y-557150D01*
X-694200Y-556567D01*
X-693950Y-555750D01*
X-694117Y-554933D01*
X-694533Y-554233D01*
X-695283Y-553767D01*
X-696283Y-553533D01*
X-696867Y-553067D01*
X-697117Y-552250D01*
X-696950Y-551433D01*
X-696533Y-550850D01*
X-695950Y-550500D01*
X-695367D01*
X-694783Y-550733D01*
X-694283Y-551317D01*
G01X-684267Y-557500D02*
Y-550500D01*
X-682100Y-556333D01*
X-679933Y-550500D01*
Y-557500D01*
G01X-677383D02*
X-675300Y-550500D01*
X-673217Y-557500D01*
G01X-673967Y-555050D02*
X-676633D01*
G01X-668500Y-557500D02*
Y-554350D01*
X-670167Y-550500D01*
G01X-666833D02*
X-668500Y-554350D01*
G01X-656817Y-557500D02*
Y-550500D01*
X-652983Y-557500D01*
Y-550500D01*
G01X-648100Y-557500D02*
X-648767Y-557383D01*
X-649350Y-556917D01*
X-649850Y-556217D01*
X-650183Y-555400D01*
X-650350Y-554467D01*
Y-553533D01*
X-650183Y-552600D01*
X-649850Y-551783D01*
X-649350Y-551083D01*
X-648767Y-550617D01*
X-648100Y-550500D01*
X-647433Y-550617D01*
X-646850Y-551083D01*
X-646350Y-551783D01*
X-646017Y-552600D01*
X-645850Y-553533D01*
Y-554467D01*
X-646017Y-555400D01*
X-646350Y-556217D01*
X-646850Y-556917D01*
X-647433Y-557383D01*
X-648100Y-557500D01*
G01X-641300Y-550500D02*
Y-557500D01*
G01X-643217Y-550500D02*
X-639383D01*
G01X-627033Y-553767D02*
X-626700Y-553417D01*
X-626450Y-552833D01*
X-626283Y-552017D01*
X-626450Y-551317D01*
X-626783Y-550850D01*
X-627367Y-550500D01*
X-629617D01*
Y-557500D01*
X-626867D01*
X-626283Y-557033D01*
X-625950Y-556333D01*
X-625783Y-555517D01*
X-625950Y-554700D01*
X-626450Y-554000D01*
X-627033Y-553767D01*
X-629617D01*
G01X-619233Y-557500D02*
X-622567D01*
Y-550500D01*
X-619233D01*
G01X-620567Y-553883D02*
X-622567D01*
G01X-870667Y-536083D02*
X-871167Y-535733D01*
X-871750Y-535500D01*
X-872417D01*
X-873167Y-535850D01*
X-873750Y-536433D01*
X-874167Y-537133D01*
X-874500Y-538300D01*
X-874583Y-539350D01*
X-874417Y-540400D01*
X-874167Y-541100D01*
X-873667Y-541800D01*
X-873083Y-542267D01*
X-872500Y-542500D01*
X-871917D01*
X-871333Y-542267D01*
X-870833Y-541917D01*
X-870417Y-541450D01*
G01X-865700Y-542500D02*
X-866367Y-542383D01*
X-866950Y-541917D01*
X-867450Y-541217D01*
X-867783Y-540400D01*
X-867950Y-539467D01*
Y-538533D01*
X-867783Y-537600D01*
X-867450Y-536783D01*
X-866950Y-536083D01*
X-866367Y-535617D01*
X-865700Y-535500D01*
X-865033Y-535617D01*
X-864450Y-536083D01*
X-863950Y-536783D01*
X-863617Y-537600D01*
X-863450Y-538533D01*
Y-539467D01*
X-863617Y-540400D01*
X-863950Y-541217D01*
X-864450Y-541917D01*
X-865033Y-542383D01*
X-865700Y-542500D01*
G01X-860567D02*
Y-535500D01*
X-858483D01*
X-857817Y-535850D01*
X-857400Y-536317D01*
X-857233Y-537250D01*
X-857400Y-538183D01*
X-857900Y-538767D01*
X-858483Y-539117D01*
X-860567D01*
G01X-858483D02*
X-857233Y-542500D01*
G01X-853767D02*
Y-535500D01*
X-851767D01*
X-851100Y-535850D01*
X-850600Y-536667D01*
X-850433Y-537600D01*
X-850600Y-538533D01*
X-851017Y-539233D01*
X-851767Y-539584D01*
X-853767D01*
G01X-845300Y-542500D02*
X-845967Y-542383D01*
X-846550Y-541917D01*
X-847050Y-541217D01*
X-847383Y-540400D01*
X-847550Y-539467D01*
Y-538533D01*
X-847383Y-537600D01*
X-847050Y-536783D01*
X-846550Y-536083D01*
X-845967Y-535617D01*
X-845300Y-535500D01*
X-844633Y-535617D01*
X-844050Y-536083D01*
X-843550Y-536783D01*
X-843217Y-537600D01*
X-843050Y-538533D01*
Y-539467D01*
X-843217Y-540400D01*
X-843550Y-541217D01*
X-844050Y-541917D01*
X-844633Y-542383D01*
X-845300Y-542500D01*
G01X-840167D02*
Y-535500D01*
X-838083D01*
X-837417Y-535850D01*
X-837000Y-536317D01*
X-836833Y-537250D01*
X-837000Y-538183D01*
X-837500Y-538767D01*
X-838083Y-539117D01*
X-840167D01*
G01X-838083D02*
X-836833Y-542500D01*
G01X-833783D02*
X-831700Y-535500D01*
X-829617Y-542500D01*
G01X-830367Y-540050D02*
X-833033D01*
G01X-824900Y-535500D02*
Y-542500D01*
G01X-826817Y-535500D02*
X-822983D01*
G01X-819100D02*
X-817100D01*
G01X-818100D02*
Y-542500D01*
G01X-819100D02*
X-817100D01*
G01X-811300D02*
X-811967Y-542383D01*
X-812550Y-541917D01*
X-813050Y-541217D01*
X-813383Y-540400D01*
X-813550Y-539467D01*
Y-538533D01*
X-813383Y-537600D01*
X-813050Y-536783D01*
X-812550Y-536083D01*
X-811967Y-535617D01*
X-811300Y-535500D01*
X-810633Y-535617D01*
X-810050Y-536083D01*
X-809550Y-536783D01*
X-809217Y-537600D01*
X-809050Y-538533D01*
Y-539467D01*
X-809217Y-540400D01*
X-809550Y-541217D01*
X-810050Y-541917D01*
X-810633Y-542383D01*
X-811300Y-542500D01*
G01X-806417D02*
Y-535500D01*
X-802583Y-542500D01*
Y-535500D01*
G01X-797700Y-542733D02*
X-797867Y-542617D01*
Y-542383D01*
X-797700Y-542267D01*
X-797533Y-542383D01*
Y-542617D01*
X-797700Y-542733D01*
G01X-784100Y-535500D02*
Y-542500D01*
G01X-786017Y-535500D02*
X-782183D01*
G01X-779050Y-542500D02*
Y-535500D01*
G01X-775550D02*
Y-542500D01*
G01Y-539000D02*
X-779050D01*
G01X-771500Y-535500D02*
X-769500D01*
G01X-770500D02*
Y-542500D01*
G01X-771500D02*
X-769500D01*
G01X-765450Y-541567D02*
X-764783Y-542150D01*
X-764033Y-542500D01*
X-763367D01*
X-762700Y-542150D01*
X-762200Y-541567D01*
X-761950Y-540750D01*
X-762117Y-539933D01*
X-762533Y-539233D01*
X-763283Y-538767D01*
X-764283Y-538533D01*
X-764867Y-538067D01*
X-765117Y-537250D01*
X-764950Y-536433D01*
X-764533Y-535850D01*
X-763950Y-535500D01*
X-763367D01*
X-762783Y-535733D01*
X-762283Y-536317D01*
G01X-751933Y-542500D02*
Y-535500D01*
X-750267D01*
X-749600Y-535850D01*
X-749100Y-536317D01*
X-748683Y-537017D01*
X-748350Y-537833D01*
X-748267Y-539000D01*
X-748350Y-540167D01*
X-748683Y-540983D01*
X-749100Y-541684D01*
X-749600Y-542150D01*
X-750267Y-542500D01*
X-751933D01*
G01X-744967D02*
Y-535500D01*
X-742883D01*
X-742217Y-535850D01*
X-741800Y-536317D01*
X-741633Y-537250D01*
X-741800Y-538183D01*
X-742300Y-538767D01*
X-742883Y-539117D01*
X-744967D01*
G01X-742883D02*
X-741633Y-542500D01*
G01X-738583D02*
X-736500Y-535500D01*
X-734417Y-542500D01*
G01X-735167Y-540050D02*
X-737833D01*
G01X-732200Y-535500D02*
X-731033Y-542500D01*
X-729700Y-535500D01*
X-728367Y-542500D01*
X-727200Y-535500D01*
G01X-723900D02*
X-721900D01*
G01X-722900D02*
Y-542500D01*
G01X-723900D02*
X-721900D01*
G01X-718017D02*
Y-535500D01*
X-714183Y-542500D01*
Y-535500D01*
G01X-708800Y-539000D02*
X-707133D01*
Y-541100D01*
X-707633Y-541800D01*
X-708217Y-542267D01*
X-709050Y-542500D01*
X-709883Y-542267D01*
X-710467Y-541800D01*
X-710967Y-541100D01*
X-711300Y-540283D01*
X-711467Y-539350D01*
Y-538533D01*
X-711300Y-537833D01*
X-710967Y-537017D01*
X-710467Y-536317D01*
X-709967Y-535850D01*
X-709300Y-535500D01*
X-708717D01*
X-708050Y-535733D01*
X-707550Y-536200D01*
G01X-696700Y-535500D02*
X-694700D01*
G01X-695700D02*
Y-542500D01*
G01X-696700D02*
X-694700D01*
G01X-690650Y-541567D02*
X-689983Y-542150D01*
X-689233Y-542500D01*
X-688567D01*
X-687900Y-542150D01*
X-687400Y-541567D01*
X-687150Y-540750D01*
X-687317Y-539933D01*
X-687733Y-539233D01*
X-688483Y-538767D01*
X-689483Y-538533D01*
X-690067Y-538067D01*
X-690317Y-537250D01*
X-690150Y-536433D01*
X-689733Y-535850D01*
X-689150Y-535500D01*
X-688567D01*
X-687983Y-535733D01*
X-687483Y-536317D01*
G01X-676967Y-542500D02*
Y-535500D01*
X-674883D01*
X-674217Y-535850D01*
X-673800Y-536317D01*
X-673633Y-537250D01*
X-673800Y-538183D01*
X-674300Y-538767D01*
X-674883Y-539117D01*
X-676967D01*
G01X-674883D02*
X-673633Y-542500D01*
G01X-666833D02*
X-670167D01*
Y-535500D01*
X-666833D01*
G01X-668167Y-538883D02*
X-670167D01*
G01X-659867Y-536083D02*
X-660367Y-535733D01*
X-660950Y-535500D01*
X-661617D01*
X-662367Y-535850D01*
X-662950Y-536433D01*
X-663367Y-537133D01*
X-663700Y-538300D01*
X-663783Y-539350D01*
X-663617Y-540400D01*
X-663367Y-541100D01*
X-662867Y-541800D01*
X-662283Y-542267D01*
X-661700Y-542500D01*
X-661117D01*
X-660533Y-542267D01*
X-660033Y-541917D01*
X-659617Y-541450D01*
G01X-653233Y-542500D02*
X-656567D01*
Y-535500D01*
X-653233D01*
G01X-654567Y-538883D02*
X-656567D01*
G01X-649100Y-535500D02*
X-647100D01*
G01X-648100D02*
Y-542500D01*
G01X-649100D02*
X-647100D01*
G01X-643383Y-535500D02*
X-641300Y-542500D01*
X-639217Y-535500D01*
G01X-632833Y-542500D02*
X-636167D01*
Y-535500D01*
X-632833D01*
G01X-634167Y-538883D02*
X-636167D01*
G01X-629533Y-542500D02*
Y-535500D01*
X-627867D01*
X-627200Y-535850D01*
X-626700Y-536317D01*
X-626283Y-537017D01*
X-625950Y-537833D01*
X-625867Y-539000D01*
X-625950Y-540167D01*
X-626283Y-540983D01*
X-626700Y-541684D01*
X-627200Y-542150D01*
X-627867Y-542500D01*
X-629533D01*
G01X-615100Y-535500D02*
X-613100D01*
G01X-614100D02*
Y-542500D01*
G01X-615100D02*
X-613100D01*
G01X-609217D02*
Y-535500D01*
X-605383Y-542500D01*
Y-535500D01*
G01X-872500Y-520500D02*
Y-527500D01*
G01X-874417Y-520500D02*
X-870583D01*
G01X-867450Y-527500D02*
Y-520500D01*
G01X-863950D02*
Y-527500D01*
G01Y-524000D02*
X-867450D01*
G01X-857233Y-527500D02*
X-860567D01*
Y-520500D01*
X-857233D01*
G01X-858567Y-523883D02*
X-860567D01*
G01X-846967Y-527500D02*
Y-520500D01*
X-844967D01*
X-844300Y-520850D01*
X-843800Y-521667D01*
X-843633Y-522600D01*
X-843800Y-523533D01*
X-844217Y-524233D01*
X-844967Y-524584D01*
X-846967D01*
G01X-840167Y-527500D02*
Y-520500D01*
X-838083D01*
X-837417Y-520850D01*
X-837000Y-521317D01*
X-836833Y-522250D01*
X-837000Y-523183D01*
X-837500Y-523767D01*
X-838083Y-524117D01*
X-840167D01*
G01X-838083D02*
X-836833Y-527500D01*
G01X-831700D02*
X-832367Y-527383D01*
X-832950Y-526917D01*
X-833450Y-526217D01*
X-833783Y-525400D01*
X-833950Y-524467D01*
Y-523533D01*
X-833783Y-522600D01*
X-833450Y-521783D01*
X-832950Y-521083D01*
X-832367Y-520617D01*
X-831700Y-520500D01*
X-831033Y-520617D01*
X-830450Y-521083D01*
X-829950Y-521783D01*
X-829617Y-522600D01*
X-829450Y-523533D01*
Y-524467D01*
X-829617Y-525400D01*
X-829950Y-526217D01*
X-830450Y-526917D01*
X-831033Y-527383D01*
X-831700Y-527500D01*
G01X-826567D02*
Y-520500D01*
X-824567D01*
X-823900Y-520850D01*
X-823400Y-521667D01*
X-823233Y-522600D01*
X-823400Y-523533D01*
X-823817Y-524233D01*
X-824567Y-524584D01*
X-826567D01*
G01X-819767Y-527500D02*
Y-520500D01*
X-817683D01*
X-817017Y-520850D01*
X-816600Y-521317D01*
X-816433Y-522250D01*
X-816600Y-523183D01*
X-817100Y-523767D01*
X-817683Y-524117D01*
X-819767D01*
G01X-817683D02*
X-816433Y-527500D01*
G01X-812300Y-520500D02*
X-810300D01*
G01X-811300D02*
Y-527500D01*
G01X-812300D02*
X-810300D01*
G01X-802833D02*
X-806167D01*
Y-520500D01*
X-802833D01*
G01X-804167Y-523883D02*
X-806167D01*
G01X-797700Y-520500D02*
Y-527500D01*
G01X-799617Y-520500D02*
X-795783D01*
G01X-792983Y-527500D02*
X-790900Y-520500D01*
X-788817Y-527500D01*
G01X-789567Y-525050D02*
X-792233D01*
G01X-785767Y-527500D02*
Y-520500D01*
X-783683D01*
X-783017Y-520850D01*
X-782600Y-521317D01*
X-782433Y-522250D01*
X-782600Y-523183D01*
X-783100Y-523767D01*
X-783683Y-524117D01*
X-785767D01*
G01X-783683D02*
X-782433Y-527500D01*
G01X-777300D02*
Y-524350D01*
X-778967Y-520500D01*
G01X-775633D02*
X-777300Y-524350D01*
G01X-765367Y-527500D02*
Y-520500D01*
X-763367D01*
X-762700Y-520850D01*
X-762200Y-521667D01*
X-762033Y-522600D01*
X-762200Y-523533D01*
X-762617Y-524233D01*
X-763367Y-524584D01*
X-765367D01*
G01X-758567Y-527500D02*
Y-520500D01*
X-756483D01*
X-755817Y-520850D01*
X-755400Y-521317D01*
X-755233Y-522250D01*
X-755400Y-523183D01*
X-755900Y-523767D01*
X-756483Y-524117D01*
X-758567D01*
G01X-756483D02*
X-755233Y-527500D01*
G01X-750100D02*
X-750767Y-527383D01*
X-751350Y-526917D01*
X-751850Y-526217D01*
X-752183Y-525400D01*
X-752350Y-524467D01*
Y-523533D01*
X-752183Y-522600D01*
X-751850Y-521783D01*
X-751350Y-521083D01*
X-750767Y-520617D01*
X-750100Y-520500D01*
X-749433Y-520617D01*
X-748850Y-521083D01*
X-748350Y-521783D01*
X-748017Y-522600D01*
X-747850Y-523533D01*
Y-524467D01*
X-748017Y-525400D01*
X-748350Y-526217D01*
X-748850Y-526917D01*
X-749433Y-527383D01*
X-750100Y-527500D01*
G01X-744967D02*
Y-520500D01*
X-742967D01*
X-742300Y-520850D01*
X-741800Y-521667D01*
X-741633Y-522600D01*
X-741800Y-523533D01*
X-742217Y-524233D01*
X-742967Y-524584D01*
X-744967D01*
G01X-734833Y-527500D02*
X-738167D01*
Y-520500D01*
X-734833D01*
G01X-736167Y-523883D02*
X-738167D01*
G01X-731367Y-527500D02*
Y-520500D01*
X-729283D01*
X-728617Y-520850D01*
X-728200Y-521317D01*
X-728033Y-522250D01*
X-728200Y-523183D01*
X-728700Y-523767D01*
X-729283Y-524117D01*
X-731367D01*
G01X-729283D02*
X-728033Y-527500D01*
G01X-722900Y-520500D02*
Y-527500D01*
G01X-724817Y-520500D02*
X-720983D01*
G01X-716100Y-527500D02*
Y-524350D01*
X-717767Y-520500D01*
G01X-714433D02*
X-716100Y-524350D01*
G01X-702500Y-527500D02*
X-703167Y-527383D01*
X-703750Y-526917D01*
X-704250Y-526217D01*
X-704583Y-525400D01*
X-704750Y-524467D01*
Y-523533D01*
X-704583Y-522600D01*
X-704250Y-521783D01*
X-703750Y-521083D01*
X-703167Y-520617D01*
X-702500Y-520500D01*
X-701833Y-520617D01*
X-701250Y-521083D01*
X-700750Y-521783D01*
X-700417Y-522600D01*
X-700250Y-523533D01*
Y-524467D01*
X-700417Y-525400D01*
X-700750Y-526217D01*
X-701250Y-526917D01*
X-701833Y-527383D01*
X-702500Y-527500D01*
G01X-697283D02*
Y-520500D01*
X-694117D01*
G01X-695283Y-523883D02*
X-697283D01*
G01X-684267Y-527500D02*
Y-520500D01*
X-682100Y-526333D01*
X-679933Y-520500D01*
Y-527500D01*
G01X-676300Y-520500D02*
X-674300D01*
G01X-675300D02*
Y-527500D01*
G01X-676300D02*
X-674300D01*
G01X-666667Y-521083D02*
X-667167Y-520733D01*
X-667750Y-520500D01*
X-668417D01*
X-669167Y-520850D01*
X-669750Y-521433D01*
X-670167Y-522133D01*
X-670500Y-523300D01*
X-670583Y-524350D01*
X-670417Y-525400D01*
X-670167Y-526100D01*
X-669667Y-526800D01*
X-669083Y-527267D01*
X-668500Y-527500D01*
X-667917D01*
X-667333Y-527267D01*
X-666833Y-526917D01*
X-666417Y-526450D01*
G01X-663367Y-527500D02*
Y-520500D01*
X-661283D01*
X-660617Y-520850D01*
X-660200Y-521317D01*
X-660033Y-522250D01*
X-660200Y-523183D01*
X-660700Y-523767D01*
X-661283Y-524117D01*
X-663367D01*
G01X-661283D02*
X-660033Y-527500D01*
G01X-654900D02*
X-655567Y-527383D01*
X-656150Y-526917D01*
X-656650Y-526217D01*
X-656983Y-525400D01*
X-657150Y-524467D01*
Y-523533D01*
X-656983Y-522600D01*
X-656650Y-521783D01*
X-656150Y-521083D01*
X-655567Y-520617D01*
X-654900Y-520500D01*
X-654233Y-520617D01*
X-653650Y-521083D01*
X-653150Y-521783D01*
X-652817Y-522600D01*
X-652650Y-523533D01*
Y-524467D01*
X-652817Y-525400D01*
X-653150Y-526217D01*
X-653650Y-526917D01*
X-654233Y-527383D01*
X-654900Y-527500D01*
G01X-649850Y-526567D02*
X-649183Y-527150D01*
X-648433Y-527500D01*
X-647767D01*
X-647100Y-527150D01*
X-646600Y-526567D01*
X-646350Y-525750D01*
X-646517Y-524933D01*
X-646933Y-524233D01*
X-647683Y-523767D01*
X-648683Y-523533D01*
X-649267Y-523067D01*
X-649517Y-522250D01*
X-649350Y-521433D01*
X-648933Y-520850D01*
X-648350Y-520500D01*
X-647767D01*
X-647183Y-520733D01*
X-646683Y-521317D01*
G01X-641300Y-527500D02*
X-641967Y-527383D01*
X-642550Y-526917D01*
X-643050Y-526217D01*
X-643383Y-525400D01*
X-643550Y-524467D01*
Y-523533D01*
X-643383Y-522600D01*
X-643050Y-521783D01*
X-642550Y-521083D01*
X-641967Y-520617D01*
X-641300Y-520500D01*
X-640633Y-520617D01*
X-640050Y-521083D01*
X-639550Y-521783D01*
X-639217Y-522600D01*
X-639050Y-523533D01*
Y-524467D01*
X-639217Y-525400D01*
X-639550Y-526217D01*
X-640050Y-526917D01*
X-640633Y-527383D01*
X-641300Y-527500D01*
G01X-636083D02*
Y-520500D01*
X-632917D01*
G01X-634083Y-523883D02*
X-636083D01*
G01X-627700Y-520500D02*
Y-527500D01*
G01X-629617Y-520500D02*
X-625783D01*
G01X-872500Y-505500D02*
Y-512500D01*
G01X-874417Y-505500D02*
X-870583D01*
G01X-867450Y-512500D02*
Y-505500D01*
G01X-863950D02*
Y-512500D01*
G01Y-509000D02*
X-867450D01*
G01X-859900Y-505500D02*
X-857900D01*
G01X-858900D02*
Y-512500D01*
G01X-859900D02*
X-857900D01*
G01X-853850Y-511567D02*
X-853183Y-512150D01*
X-852433Y-512500D01*
X-851767D01*
X-851100Y-512150D01*
X-850600Y-511567D01*
X-850350Y-510750D01*
X-850517Y-509933D01*
X-850933Y-509233D01*
X-851683Y-508767D01*
X-852683Y-508533D01*
X-853267Y-508067D01*
X-853517Y-507250D01*
X-853350Y-506433D01*
X-852933Y-505850D01*
X-852350Y-505500D01*
X-851767D01*
X-851183Y-505733D01*
X-850683Y-506317D01*
G01X-840333Y-512500D02*
Y-505500D01*
X-838667D01*
X-838000Y-505850D01*
X-837500Y-506317D01*
X-837083Y-507017D01*
X-836750Y-507833D01*
X-836667Y-509000D01*
X-836750Y-510167D01*
X-837083Y-510983D01*
X-837500Y-511684D01*
X-838000Y-512150D01*
X-838667Y-512500D01*
X-840333D01*
G01X-833367D02*
Y-505500D01*
X-831283D01*
X-830617Y-505850D01*
X-830200Y-506317D01*
X-830033Y-507250D01*
X-830200Y-508183D01*
X-830700Y-508767D01*
X-831283Y-509117D01*
X-833367D01*
G01X-831283D02*
X-830033Y-512500D01*
G01X-826983D02*
X-824900Y-505500D01*
X-822817Y-512500D01*
G01X-823567Y-510050D02*
X-826233D01*
G01X-820600Y-505500D02*
X-819433Y-512500D01*
X-818100Y-505500D01*
X-816767Y-512500D01*
X-815600Y-505500D01*
G01X-812300D02*
X-810300D01*
G01X-811300D02*
Y-512500D01*
G01X-812300D02*
X-810300D01*
G01X-806417D02*
Y-505500D01*
X-802583Y-512500D01*
Y-505500D01*
G01X-797200Y-509000D02*
X-795533D01*
Y-511100D01*
X-796033Y-511800D01*
X-796617Y-512267D01*
X-797450Y-512500D01*
X-798283Y-512267D01*
X-798867Y-511800D01*
X-799367Y-511100D01*
X-799700Y-510283D01*
X-799867Y-509350D01*
Y-508533D01*
X-799700Y-507833D01*
X-799367Y-507017D01*
X-798867Y-506317D01*
X-798367Y-505850D01*
X-797700Y-505500D01*
X-797117D01*
X-796450Y-505733D01*
X-795950Y-506200D01*
G01X-782267Y-506083D02*
X-782767Y-505733D01*
X-783350Y-505500D01*
X-784017D01*
X-784767Y-505850D01*
X-785350Y-506433D01*
X-785767Y-507133D01*
X-786100Y-508300D01*
X-786183Y-509350D01*
X-786017Y-510400D01*
X-785767Y-511100D01*
X-785267Y-511800D01*
X-784683Y-512267D01*
X-784100Y-512500D01*
X-783517D01*
X-782933Y-512267D01*
X-782433Y-511917D01*
X-782017Y-511450D01*
G01X-777300Y-512500D02*
X-777967Y-512383D01*
X-778550Y-511917D01*
X-779050Y-511217D01*
X-779383Y-510400D01*
X-779550Y-509467D01*
Y-508533D01*
X-779383Y-507600D01*
X-779050Y-506783D01*
X-778550Y-506083D01*
X-777967Y-505617D01*
X-777300Y-505500D01*
X-776633Y-505617D01*
X-776050Y-506083D01*
X-775550Y-506783D01*
X-775217Y-507600D01*
X-775050Y-508533D01*
Y-509467D01*
X-775217Y-510400D01*
X-775550Y-511217D01*
X-776050Y-511917D01*
X-776633Y-512383D01*
X-777300Y-512500D01*
G01X-772417D02*
Y-505500D01*
X-768583Y-512500D01*
Y-505500D01*
G01X-763700D02*
Y-512500D01*
G01X-765617Y-505500D02*
X-761783D01*
G01X-758983Y-512500D02*
X-756900Y-505500D01*
X-754817Y-512500D01*
G01X-755567Y-510050D02*
X-758233D01*
G01X-751100Y-505500D02*
X-749100D01*
G01X-750100D02*
Y-512500D01*
G01X-751100D02*
X-749100D01*
G01X-745217D02*
Y-505500D01*
X-741383Y-512500D01*
Y-505500D01*
G01X-738250Y-511567D02*
X-737583Y-512150D01*
X-736833Y-512500D01*
X-736167D01*
X-735500Y-512150D01*
X-735000Y-511567D01*
X-734750Y-510750D01*
X-734917Y-509933D01*
X-735333Y-509233D01*
X-736083Y-508767D01*
X-737083Y-508533D01*
X-737667Y-508067D01*
X-737917Y-507250D01*
X-737750Y-506433D01*
X-737333Y-505850D01*
X-736750Y-505500D01*
X-736167D01*
X-735583Y-505733D01*
X-735083Y-506317D01*
G01X-723900Y-505500D02*
X-721900D01*
G01X-722900D02*
Y-512500D01*
G01X-723900D02*
X-721900D01*
G01X-718017D02*
Y-505500D01*
X-714183Y-512500D01*
Y-505500D01*
G01X-710883Y-512500D02*
Y-505500D01*
X-707717D01*
G01X-708883Y-508883D02*
X-710883D01*
G01X-702500Y-512500D02*
X-703167Y-512383D01*
X-703750Y-511917D01*
X-704250Y-511217D01*
X-704583Y-510400D01*
X-704750Y-509467D01*
Y-508533D01*
X-704583Y-507600D01*
X-704250Y-506783D01*
X-703750Y-506083D01*
X-703167Y-505617D01*
X-702500Y-505500D01*
X-701833Y-505617D01*
X-701250Y-506083D01*
X-700750Y-506783D01*
X-700417Y-507600D01*
X-700250Y-508533D01*
Y-509467D01*
X-700417Y-510400D01*
X-700750Y-511217D01*
X-701250Y-511917D01*
X-701833Y-512383D01*
X-702500Y-512500D01*
G01X-697367D02*
Y-505500D01*
X-695283D01*
X-694617Y-505850D01*
X-694200Y-506317D01*
X-694033Y-507250D01*
X-694200Y-508183D01*
X-694700Y-508767D01*
X-695283Y-509117D01*
X-697367D01*
G01X-695283D02*
X-694033Y-512500D01*
G01X-691067D02*
Y-505500D01*
X-688900Y-511333D01*
X-686733Y-505500D01*
Y-512500D01*
G01X-684183D02*
X-682100Y-505500D01*
X-680017Y-512500D01*
G01X-680767Y-510050D02*
X-683433D01*
G01X-675300Y-505500D02*
Y-512500D01*
G01X-677217Y-505500D02*
X-673383D01*
G01X-669500D02*
X-667500D01*
G01X-668500D02*
Y-512500D01*
G01X-669500D02*
X-667500D01*
G01X-661700D02*
X-662367Y-512383D01*
X-662950Y-511917D01*
X-663450Y-511217D01*
X-663783Y-510400D01*
X-663950Y-509467D01*
Y-508533D01*
X-663783Y-507600D01*
X-663450Y-506783D01*
X-662950Y-506083D01*
X-662367Y-505617D01*
X-661700Y-505500D01*
X-661033Y-505617D01*
X-660450Y-506083D01*
X-659950Y-506783D01*
X-659617Y-507600D01*
X-659450Y-508533D01*
Y-509467D01*
X-659617Y-510400D01*
X-659950Y-511217D01*
X-660450Y-511917D01*
X-661033Y-512383D01*
X-661700Y-512500D01*
G01X-656817D02*
Y-505500D01*
X-652983Y-512500D01*
Y-505500D01*
G01X-643800D02*
X-642633Y-512500D01*
X-641300Y-505500D01*
X-639967Y-512500D01*
X-638800Y-505500D01*
G01X-636250Y-512500D02*
Y-505500D01*
G01X-632750D02*
Y-512500D01*
G01Y-509000D02*
X-636250D01*
G01X-628700Y-505500D02*
X-626700D01*
G01X-627700D02*
Y-512500D01*
G01X-628700D02*
X-626700D01*
G01X-619067Y-506083D02*
X-619567Y-505733D01*
X-620150Y-505500D01*
X-620817D01*
X-621567Y-505850D01*
X-622150Y-506433D01*
X-622567Y-507133D01*
X-622900Y-508300D01*
X-622983Y-509350D01*
X-622817Y-510400D01*
X-622567Y-511100D01*
X-622067Y-511800D01*
X-621483Y-512267D01*
X-620900Y-512500D01*
X-620317D01*
X-619733Y-512267D01*
X-619233Y-511917D01*
X-618817Y-511450D01*
G01X-615850Y-512500D02*
Y-505500D01*
G01X-612350D02*
Y-512500D01*
G01Y-509000D02*
X-615850D01*
G01X-601500Y-505500D02*
X-599500D01*
G01X-600500D02*
Y-512500D01*
G01X-601500D02*
X-599500D01*
G01X-595450Y-511567D02*
X-594783Y-512150D01*
X-594033Y-512500D01*
X-593367D01*
X-592700Y-512150D01*
X-592200Y-511567D01*
X-591950Y-510750D01*
X-592117Y-509933D01*
X-592533Y-509233D01*
X-593283Y-508767D01*
X-594283Y-508533D01*
X-594867Y-508067D01*
X-595117Y-507250D01*
X-594950Y-506433D01*
X-594533Y-505850D01*
X-593950Y-505500D01*
X-593367D01*
X-592783Y-505733D01*
X-592283Y-506317D01*
G01X-858133Y-452500D02*
Y-445500D01*
X-856467D01*
X-855800Y-445850D01*
X-855300Y-446317D01*
X-854883Y-447017D01*
X-854550Y-447833D01*
X-854467Y-449000D01*
X-854550Y-450167D01*
X-854883Y-450983D01*
X-855300Y-451684D01*
X-855800Y-452150D01*
X-856467Y-452500D01*
X-858133D01*
G01X-847833D02*
X-851167D01*
Y-445500D01*
X-847833D01*
G01X-849167Y-448883D02*
X-851167D01*
G01X-844450Y-451567D02*
X-843783Y-452150D01*
X-843033Y-452500D01*
X-842367D01*
X-841700Y-452150D01*
X-841200Y-451567D01*
X-840950Y-450750D01*
X-841117Y-449933D01*
X-841533Y-449233D01*
X-842283Y-448767D01*
X-843283Y-448533D01*
X-843867Y-448067D01*
X-844117Y-447250D01*
X-843950Y-446433D01*
X-843533Y-445850D01*
X-842950Y-445500D01*
X-842367D01*
X-841783Y-445733D01*
X-841283Y-446317D01*
G01X-836900Y-445500D02*
X-834900D01*
G01X-835900D02*
Y-452500D01*
G01X-836900D02*
X-834900D01*
G01X-828600Y-449000D02*
X-826933D01*
Y-451100D01*
X-827433Y-451800D01*
X-828017Y-452267D01*
X-828850Y-452500D01*
X-829683Y-452267D01*
X-830267Y-451800D01*
X-830767Y-451100D01*
X-831100Y-450283D01*
X-831267Y-449350D01*
Y-448533D01*
X-831100Y-447833D01*
X-830767Y-447017D01*
X-830267Y-446317D01*
X-829767Y-445850D01*
X-829100Y-445500D01*
X-828517D01*
X-827850Y-445733D01*
X-827350Y-446200D01*
G01X-824217Y-452500D02*
Y-445500D01*
X-820383Y-452500D01*
Y-445500D01*
G01X-813833Y-452500D02*
X-817167D01*
Y-445500D01*
X-813833D01*
G01X-815167Y-448883D02*
X-817167D01*
G01X-810367Y-452500D02*
Y-445500D01*
X-808283D01*
X-807617Y-445850D01*
X-807200Y-446317D01*
X-807033Y-447250D01*
X-807200Y-448183D01*
X-807700Y-448767D01*
X-808283Y-449117D01*
X-810367D01*
G01X-808283D02*
X-807033Y-452500D01*
G01X-858133D02*
Y-445500D01*
X-856467D01*
X-855800Y-445850D01*
X-855300Y-446317D01*
X-854883Y-447017D01*
X-854550Y-447833D01*
X-854467Y-449000D01*
X-854550Y-450167D01*
X-854883Y-450983D01*
X-855300Y-451684D01*
X-855800Y-452150D01*
X-856467Y-452500D01*
X-858133D01*
G01X-847833D02*
X-851167D01*
Y-445500D01*
X-847833D01*
G01X-849167Y-448883D02*
X-851167D01*
G01X-844450Y-451567D02*
X-843783Y-452150D01*
X-843033Y-452500D01*
X-842367D01*
X-841700Y-452150D01*
X-841200Y-451567D01*
X-840950Y-450750D01*
X-841117Y-449933D01*
X-841533Y-449233D01*
X-842283Y-448767D01*
X-843283Y-448533D01*
X-843867Y-448067D01*
X-844117Y-447250D01*
X-843950Y-446433D01*
X-843533Y-445850D01*
X-842950Y-445500D01*
X-842367D01*
X-841783Y-445733D01*
X-841283Y-446317D01*
G01X-836900Y-445500D02*
X-834900D01*
G01X-835900D02*
Y-452500D01*
G01X-836900D02*
X-834900D01*
G01X-828600Y-449000D02*
X-826933D01*
Y-451100D01*
X-827433Y-451800D01*
X-828017Y-452267D01*
X-828850Y-452500D01*
X-829683Y-452267D01*
X-830267Y-451800D01*
X-830767Y-451100D01*
X-831100Y-450283D01*
X-831267Y-449350D01*
Y-448533D01*
X-831100Y-447833D01*
X-830767Y-447017D01*
X-830267Y-446317D01*
X-829767Y-445850D01*
X-829100Y-445500D01*
X-828517D01*
X-827850Y-445733D01*
X-827350Y-446200D01*
G01X-824217Y-452500D02*
Y-445500D01*
X-820383Y-452500D01*
Y-445500D01*
G01X-813833Y-452500D02*
X-817167D01*
Y-445500D01*
X-813833D01*
G01X-815167Y-448883D02*
X-817167D01*
G01X-810367Y-452500D02*
Y-445500D01*
X-808283D01*
X-807617Y-445850D01*
X-807200Y-446317D01*
X-807033Y-447250D01*
X-807200Y-448183D01*
X-807700Y-448767D01*
X-808283Y-449117D01*
X-810367D01*
G01X-808283D02*
X-807033Y-452500D01*
G01X-642033Y-455000D02*
Y-448000D01*
X-640367D01*
X-639700Y-448350D01*
X-639200Y-448817D01*
X-638783Y-449517D01*
X-638450Y-450333D01*
X-638367Y-451500D01*
X-638450Y-452667D01*
X-638783Y-453483D01*
X-639200Y-454184D01*
X-639700Y-454650D01*
X-640367Y-455000D01*
X-642033D01*
G01X-635483D02*
X-633400Y-448000D01*
X-631317Y-455000D01*
G01X-632067Y-452550D02*
X-634733D01*
G01X-626600Y-448000D02*
Y-455000D01*
G01X-628517Y-448000D02*
X-624683D01*
G01X-618133Y-455000D02*
X-621467D01*
Y-448000D01*
X-618133D01*
G01X-619467Y-451383D02*
X-621467D01*
G54D17*
G01X-1184000Y-502500D02*
Y-512500D01*
G01X-1186683Y-502500D02*
X-1181317D01*
G01X-1176833Y-512500D02*
Y-502500D01*
X-1173917D01*
X-1172983Y-503000D01*
X-1172400Y-503667D01*
X-1172167Y-505000D01*
X-1172400Y-506333D01*
X-1173100Y-507167D01*
X-1173917Y-507667D01*
X-1176833D01*
G01X-1173917D02*
X-1172167Y-512500D01*
G01X-1167917D02*
X-1165000Y-502500D01*
X-1162083Y-512500D01*
G01X-1163133Y-509000D02*
X-1166867D01*
G01X-1155500Y-512500D02*
Y-508000D01*
X-1157833Y-502500D01*
G01X-1153167D02*
X-1155500Y-508000D01*
G01X-1135567Y-507167D02*
X-1135100Y-506667D01*
X-1134750Y-505834D01*
X-1134517Y-504667D01*
X-1134750Y-503667D01*
X-1135217Y-503000D01*
X-1136033Y-502500D01*
X-1139183D01*
Y-512500D01*
X-1135333D01*
X-1134517Y-511833D01*
X-1134050Y-510833D01*
X-1133817Y-509667D01*
X-1134050Y-508500D01*
X-1134750Y-507500D01*
X-1135567Y-507167D01*
X-1139183D01*
G01X-1129917Y-512500D02*
X-1127000Y-502500D01*
X-1124083Y-512500D01*
G01X-1125133Y-509000D02*
X-1128867D01*
G01X-1114933Y-503333D02*
X-1115633Y-502833D01*
X-1116450Y-502500D01*
X-1117383D01*
X-1118433Y-503000D01*
X-1119250Y-503833D01*
X-1119833Y-504833D01*
X-1120300Y-506500D01*
X-1120417Y-508000D01*
X-1120183Y-509500D01*
X-1119833Y-510500D01*
X-1119133Y-511500D01*
X-1118317Y-512167D01*
X-1117500Y-512500D01*
X-1116683D01*
X-1115867Y-512167D01*
X-1115167Y-511667D01*
X-1114583Y-511000D01*
G01X-1110567Y-512500D02*
Y-502500D01*
G01X-1106133D02*
X-1110567Y-508667D01*
G01X-1105433Y-512500D02*
X-1108583Y-505834D01*
G01X-1100833Y-512500D02*
Y-502500D01*
X-1098033D01*
X-1097100Y-503000D01*
X-1096400Y-504167D01*
X-1096167Y-505500D01*
X-1096400Y-506833D01*
X-1096983Y-507833D01*
X-1098033Y-508334D01*
X-1100833D01*
G01X-1091333Y-502500D02*
Y-512500D01*
X-1086667D01*
G01X-1082417D02*
X-1079500Y-502500D01*
X-1076583Y-512500D01*
G01X-1077633Y-509000D02*
X-1081367D01*
G01X-1072683Y-512500D02*
Y-502500D01*
X-1067317Y-512500D01*
Y-502500D01*
G01X-1058167Y-512500D02*
X-1062833D01*
Y-502500D01*
X-1058167D01*
G01X-1060033Y-507333D02*
X-1062833D01*
G01X-1043717Y-512500D02*
Y-502500D01*
X-1039283D01*
G01X-1040917Y-507333D02*
X-1043717D01*
G01X-1034917Y-512500D02*
X-1032000Y-502500D01*
X-1029083Y-512500D01*
G01X-1030133Y-509000D02*
X-1033867D01*
G01X-1021567Y-507167D02*
X-1021100Y-506667D01*
X-1020750Y-505834D01*
X-1020517Y-504667D01*
X-1020750Y-503667D01*
X-1021217Y-503000D01*
X-1022033Y-502500D01*
X-1025183D01*
Y-512500D01*
X-1021333D01*
X-1020517Y-511833D01*
X-1020050Y-510833D01*
X-1019817Y-509667D01*
X-1020050Y-508500D01*
X-1020750Y-507500D01*
X-1021567Y-507167D01*
X-1025183D01*
G01X-1002567D02*
X-1002100Y-506667D01*
X-1001750Y-505834D01*
X-1001517Y-504667D01*
X-1001750Y-503667D01*
X-1002217Y-503000D01*
X-1003033Y-502500D01*
X-1006183D01*
Y-512500D01*
X-1002333D01*
X-1001517Y-511833D01*
X-1001050Y-510833D01*
X-1000817Y-509667D01*
X-1001050Y-508500D01*
X-1001750Y-507500D01*
X-1002567Y-507167D01*
X-1006183D01*
G01X-985083Y-515833D02*
X-986250Y-514167D01*
X-986833Y-512500D01*
Y-505834D01*
X-986250Y-504167D01*
X-985083Y-502500D01*
G01X-975000Y-512500D02*
X-975933Y-512333D01*
X-976750Y-511667D01*
X-977450Y-510667D01*
X-977917Y-509500D01*
X-978150Y-508167D01*
Y-506833D01*
X-977917Y-505500D01*
X-977450Y-504333D01*
X-976750Y-503333D01*
X-975933Y-502667D01*
X-975000Y-502500D01*
X-974067Y-502667D01*
X-973250Y-503333D01*
X-972550Y-504333D01*
X-972083Y-505500D01*
X-971850Y-506833D01*
Y-508167D01*
X-972083Y-509500D01*
X-972550Y-510667D01*
X-973250Y-511667D01*
X-974067Y-512333D01*
X-975000Y-512500D01*
G01X-967950Y-511167D02*
X-967017Y-512000D01*
X-965967Y-512500D01*
X-965033D01*
X-964100Y-512000D01*
X-963400Y-511167D01*
X-963050Y-510000D01*
X-963283Y-508834D01*
X-963867Y-507833D01*
X-964917Y-507167D01*
X-966317Y-506833D01*
X-967133Y-506167D01*
X-967483Y-505000D01*
X-967250Y-503833D01*
X-966667Y-503000D01*
X-965850Y-502500D01*
X-965033D01*
X-964217Y-502833D01*
X-963517Y-503667D01*
G01X-958333Y-512500D02*
Y-502500D01*
X-955533D01*
X-954600Y-503000D01*
X-953900Y-504167D01*
X-953667Y-505500D01*
X-953900Y-506833D01*
X-954483Y-507833D01*
X-955533Y-508334D01*
X-958333D01*
G01X-945917Y-515833D02*
X-944750Y-514167D01*
X-944167Y-512500D01*
Y-505834D01*
X-944750Y-504167D01*
X-945917Y-502500D01*
G01X-902000Y-470000D02*
Y-460000D01*
X-903400Y-462000D01*
G01Y-470000D02*
X-900600D01*
G01X-892500Y-470333D02*
X-892733Y-470167D01*
Y-469833D01*
X-892500Y-469667D01*
X-892267Y-469833D01*
Y-470167D01*
X-892500Y-470333D01*
G01Y-465834D02*
X-892733Y-465667D01*
Y-465333D01*
X-892500Y-465167D01*
X-892267Y-465333D01*
Y-465667D01*
X-892500Y-465834D01*
G01X-883000Y-470000D02*
Y-460000D01*
X-884400Y-462000D01*
G01Y-470000D02*
X-881600D01*
G01X-785060Y-472187D02*
X-784127Y-473020D01*
X-783077Y-473520D01*
X-782143D01*
X-781210Y-473020D01*
X-780510Y-472187D01*
X-780160Y-471020D01*
X-780393Y-469854D01*
X-780977Y-468853D01*
X-782027Y-468187D01*
X-783427Y-467853D01*
X-784243Y-467187D01*
X-784593Y-466020D01*
X-784360Y-464853D01*
X-783777Y-464020D01*
X-782960Y-463520D01*
X-782143D01*
X-781327Y-463853D01*
X-780627Y-464687D01*
G01X-775560Y-473520D02*
Y-463520D01*
G01X-770660D02*
Y-473520D01*
G01Y-468520D02*
X-775560D01*
G01X-766527Y-473520D02*
X-763610Y-463520D01*
X-760693Y-473520D01*
G01X-761743Y-470020D02*
X-765477D01*
G01X-757610Y-463520D02*
X-755977Y-473520D01*
X-754110Y-463520D01*
X-752243Y-473520D01*
X-750610Y-463520D01*
G01X-668067Y-470500D02*
X-667367Y-471667D01*
X-666433Y-472333D01*
X-665383Y-472500D01*
X-664450Y-472333D01*
X-663517Y-471500D01*
X-662933Y-470500D01*
X-662817Y-469500D01*
X-663050Y-468334D01*
X-663867Y-467500D01*
X-664683Y-467167D01*
X-665733D01*
G01X-664683D02*
X-663983Y-466667D01*
X-663400Y-465834D01*
X-663167Y-464833D01*
X-663400Y-463833D01*
X-663983Y-463000D01*
X-665033Y-462500D01*
X-666083Y-462667D01*
X-667133Y-463333D01*
G01X-656000Y-462500D02*
X-656933Y-462833D01*
X-657633Y-463667D01*
X-658100Y-464667D01*
X-658450Y-466000D01*
X-658567Y-467500D01*
X-658450Y-469000D01*
X-658100Y-470333D01*
X-657633Y-471334D01*
X-656933Y-472167D01*
X-656000Y-472500D01*
X-655067Y-472167D01*
X-654367Y-471334D01*
X-653900Y-470333D01*
X-653550Y-469000D01*
X-653433Y-467500D01*
X-653550Y-466000D01*
X-653900Y-464667D01*
X-654367Y-463667D01*
X-655067Y-462833D01*
X-656000Y-462500D01*
G01X-648017Y-469167D02*
X-644983D01*
G01X-639917Y-472500D02*
X-637000Y-462500D01*
X-634083Y-472500D01*
G01X-635133Y-469000D02*
X-638867D01*
G01X-629833Y-472500D02*
Y-462500D01*
X-627033D01*
X-626100Y-463000D01*
X-625400Y-464167D01*
X-625167Y-465500D01*
X-625400Y-466833D01*
X-625983Y-467833D01*
X-627033Y-468334D01*
X-629833D01*
G01X-620333Y-472500D02*
Y-462500D01*
X-617417D01*
X-616483Y-463000D01*
X-615900Y-463667D01*
X-615667Y-465000D01*
X-615900Y-466333D01*
X-616600Y-467167D01*
X-617417Y-467667D01*
X-620333D01*
G01X-617417D02*
X-615667Y-472500D01*
G01X-610017Y-469167D02*
X-606983D01*
G01X-599000Y-472500D02*
Y-462500D01*
X-600400Y-464500D01*
G01Y-472500D02*
X-597600D01*
G01X-588100D02*
Y-462500D01*
X-592417Y-469667D01*
X-586583D01*
G54D27*
G01X-1020800Y-457700D02*
G02X-1020300Y-458200I0J-500D01*
G01Y-458400D01*
G02X-1020900Y-459000I-600J0D01*
G01X-1021300D01*
G01X-1021800Y-460500D02*
Y-457700D01*
X-1020600D01*
G01X-1018340Y-459100D02*
G03I-2660J0D01*
G01X-1020700D02*
X-1020200Y-460500D01*
G54D18*
G01X-191000Y-56400D02*
X-212180D01*
X-228580Y-72800D01*
X-239300D01*
X-247800Y-81300D01*
Y-86700D01*
X-263700Y-102600D01*
Y-115300D01*
X-270400Y-122000D01*
X-330900D01*
X-352860Y-143960D01*
X-358970D01*
X-369390Y-154380D01*
Y-171590D01*
X-371063Y-173263D01*
Y-178998D01*
G01X-374213Y-177998D02*
Y-166513D01*
X-372600Y-164900D01*
Y-151790D01*
X-361610Y-140800D01*
X-355690D01*
X-324490Y-109600D01*
X-297400D01*
X-265300Y-77500D01*
X-262300D01*
X-239900Y-55100D01*
X-237550D01*
X-211350Y-28900D01*
X-190300D01*
G01X-375800Y-154000D02*
Y-138070D01*
X-343030Y-105300D01*
X-299800D01*
X-292500Y-98000D01*
Y-95200D01*
X-269700Y-72400D01*
X-265300D01*
X-261200Y-68300D01*
Y-65550D01*
X-209280Y-13630D01*
X-199730D01*
X-190300Y-4200D01*
G01X-191000Y-56400D02*
X-186100D01*
X-185900Y-56200D01*
G01X-190300Y-28900D02*
X-183800D01*
X-182900Y-29800D01*
G01X-190300Y-4200D02*
X-183600D01*
X-183200Y-4600D01*
G54D19*
G01X-1174900Y-473500D02*
X-1171300Y-466100D01*
X-1171800Y-465700D01*
X-1175900Y-473200D01*
X-1176200Y-471200D01*
X-1172500Y-465400D01*
X-1175700Y-471300D01*
X-1176500Y-469800D01*
X-1172900Y-464900D01*
X-1173600Y-451800D01*
X-1173700Y-449900D01*
X-1182100D01*
X-1187400Y-473000D01*
X-1182400D01*
X-1177800Y-456000D01*
X-1177000Y-455900D01*
X-1176100Y-468500D01*
X-1173700Y-464500D01*
X-1174600Y-450800D01*
X-1181500Y-450900D01*
X-1186400Y-472100D01*
X-1183100D01*
X-1178300Y-454800D01*
X-1176600Y-455000D01*
X-1175500Y-466300D01*
X-1174600Y-464300D01*
X-1175400Y-451700D01*
X-1181000Y-451800D01*
X-1185300Y-471300D01*
X-1183800Y-471400D01*
X-1179000Y-454300D01*
X-1176200D01*
X-1175200Y-462200D01*
X-1176200Y-452500D01*
X-1180500Y-452800D01*
X-1184300Y-470600D01*
X-1179700Y-453400D01*
X-1176800D01*
G01X-1182820Y-448900D02*
X-1188360Y-473900D01*
X-1181580D01*
X-1177300Y-456700D01*
X-1176920Y-473900D01*
X-1172260D01*
X-1163400Y-456920D01*
X-1167240Y-473900D01*
X-1160380D01*
X-1154840Y-448900D01*
X-1164540D01*
X-1172540Y-464820D01*
X-1172880Y-448900D01*
X-1182820D01*
G01X-1155800Y-449500D02*
X-1161100Y-472900D01*
X-1166100Y-473000D01*
X-1166000Y-471900D01*
X-1161800Y-472100D01*
X-1161300Y-471000D01*
X-1165900Y-471100D01*
X-1165700Y-470000D01*
X-1161300D01*
X-1160800Y-469200D01*
X-1165300Y-469100D01*
X-1165200Y-468100D01*
X-1160700D01*
X-1160400Y-467100D01*
X-1165100Y-467200D01*
X-1164900Y-466300D01*
X-1160300Y-466200D01*
X-1160000Y-465200D01*
X-1164700Y-465300D01*
X-1164400Y-464200D01*
X-1159700Y-464300D01*
X-1159300Y-463100D01*
X-1164700Y-463500D01*
X-1164000Y-462500D01*
X-1159500Y-462600D01*
X-1159000Y-461700D01*
X-1163900D01*
X-1163600Y-460600D01*
X-1159100Y-460800D01*
X-1158800Y-459900D01*
X-1163200D01*
X-1163100Y-459200D01*
X-1158800D01*
X-1158300Y-458500D01*
X-1163000Y-458400D01*
X-1162900Y-457800D01*
X-1158400Y-457900D01*
X-1158200Y-457200D01*
X-1162500Y-457000D01*
X-1163100Y-456500D01*
X-1157800D01*
X-1157500Y-455500D01*
X-1156600Y-449800D01*
X-1164000D01*
X-1164500Y-450700D01*
X-1157600D01*
X-1157800Y-451700D01*
X-1165000Y-451600D01*
X-1165400Y-452400D01*
X-1157900Y-452500D01*
X-1157800Y-453500D01*
X-1165900Y-453200D01*
X-1166200Y-453900D01*
X-1158000Y-454300D01*
X-1158300Y-455300D01*
X-1166600Y-454800D01*
X-1158900Y-455900D01*
X-1167000Y-455600D01*
X-1163500Y-456400D01*
X-1167300Y-456300D01*
X-1171700Y-465200D01*
X-1169200Y-466400D01*
X-1164500Y-457200D01*
X-1166900Y-457100D01*
X-1170600Y-465200D01*
X-1169500Y-465500D01*
X-1166000Y-457800D01*
G01X-1170300Y-466300D02*
X-1174000Y-473600D01*
G01X-1169500Y-466900D02*
X-1172800Y-473000D01*
G01X-1152800Y-456400D02*
X-1156600Y-473100D01*
X-1152200Y-473000D01*
X-1148300Y-456600D01*
X-1149500D01*
X-1152900Y-472000D01*
X-1155600Y-472300D01*
X-1152100Y-456500D01*
X-1150400Y-456400D01*
X-1153600Y-471200D01*
X-1154500Y-471400D01*
X-1151400Y-457200D01*
G01X-1153420Y-455700D02*
X-1157540Y-473900D01*
X-1151380D01*
X-1147440Y-455700D01*
X-1153420D01*
G01X-1151600Y-450100D02*
X-1146700Y-450000D01*
X-1147000Y-451000D01*
X-1151700D01*
G01X-1152020Y-448900D02*
X-1152660Y-451900D01*
X-1146380D01*
X-1145740Y-448900D01*
X-1152020D01*
G01X-1129400Y-468900D02*
X-1131800Y-471900D01*
X-1136500Y-473700D01*
X-1142100Y-473600D01*
X-1144600Y-472300D01*
X-1145800Y-471000D01*
X-1146400Y-469500D01*
X-1146700Y-467600D01*
X-1146500Y-464600D01*
X-1145400Y-461200D01*
X-1143500Y-459100D01*
X-1140200Y-456900D01*
X-1136100Y-456200D01*
X-1132300Y-456400D01*
X-1129400Y-457900D01*
X-1127500Y-460900D01*
X-1132500Y-461000D01*
X-1133400Y-459200D01*
X-1135100Y-458100D01*
X-1136800Y-458000D01*
X-1138600Y-458900D01*
X-1140300Y-460700D01*
X-1141800Y-463600D01*
X-1142400Y-466600D01*
X-1141500Y-470400D01*
X-1140200Y-471500D01*
X-1138300Y-471600D01*
X-1136300Y-471400D01*
X-1134500Y-469100D01*
X-1130300Y-469000D01*
X-1132500Y-471200D01*
X-1134900Y-472000D01*
X-1137200Y-472800D01*
X-1142300Y-472700D01*
X-1144900Y-470600D01*
X-1145800Y-467400D01*
X-1145500Y-465100D01*
X-1144700Y-462000D01*
X-1143300Y-460200D01*
X-1139800Y-457700D01*
X-1135400Y-457000D01*
X-1131300Y-457600D01*
X-1128800Y-460100D01*
X-1132100D01*
X-1134300Y-457900D01*
X-1130100Y-458800D01*
X-1129500Y-459400D01*
X-1132600Y-459000D01*
G01X-1133300Y-461900D02*
Y-461420D01*
X-1133640Y-460240D01*
X-1134300Y-459200D01*
X-1135200Y-458900D01*
X-1136580D01*
X-1138060Y-459820D01*
X-1139360Y-461000D01*
X-1140240Y-462220D01*
X-1140880Y-463920D01*
X-1141300Y-465380D01*
X-1141500Y-467060D01*
Y-468020D01*
X-1141020Y-469220D01*
X-1139780Y-470700D01*
X-1137160D01*
X-1135840Y-469500D01*
X-1134980Y-468200D01*
X-1134940Y-468100D01*
X-1128180D01*
X-1128240Y-468240D01*
X-1128840Y-469340D01*
X-1129020Y-469800D01*
X-1129740Y-470700D01*
X-1130500Y-471460D01*
X-1131660Y-472420D01*
X-1132820Y-473200D01*
X-1133740Y-473740D01*
X-1136380Y-474500D01*
X-1141640D01*
X-1142540Y-474320D01*
X-1144220Y-473760D01*
X-1144900Y-473240D01*
X-1146240Y-471900D01*
X-1146780Y-471180D01*
X-1146940Y-470880D01*
X-1147320Y-469660D01*
X-1147500Y-468640D01*
Y-464780D01*
X-1146940Y-462540D01*
X-1146380Y-461580D01*
X-1145980Y-460780D01*
X-1145420Y-459880D01*
X-1143700Y-458140D01*
X-1142740Y-457380D01*
X-1142000Y-456820D01*
X-1140240Y-456040D01*
X-1139500Y-455660D01*
X-1138800Y-455480D01*
X-1137260Y-455300D01*
X-1134320D01*
X-1132020Y-455500D01*
X-1130940Y-455860D01*
X-1130580Y-456020D01*
X-1129260Y-456780D01*
X-1128940Y-457100D01*
X-1127820Y-458420D01*
X-1127060Y-460300D01*
X-1126900Y-460800D01*
Y-461900D01*
X-1133300D01*
G01X-1137900Y-458000D02*
X-1140300Y-459100D01*
X-1142500Y-460900D01*
X-1143900Y-462600D01*
X-1144800Y-467600D01*
X-1144200Y-470000D01*
X-1141000Y-472300D01*
X-1136400Y-472200D01*
X-1131600Y-469600D01*
X-1135400Y-470400D01*
X-1141100Y-471400D01*
X-1142100Y-470700D01*
X-1142700Y-469000D01*
X-1143100Y-467100D01*
X-1142700Y-464100D01*
X-1140500Y-459900D01*
X-1143400Y-463700D01*
X-1143600Y-465700D01*
X-1143900Y-467700D01*
X-1143000Y-469900D01*
G01X-1113500Y-459200D02*
X-1123500Y-459300D01*
X-1123700Y-460100D01*
X-1114300Y-460000D01*
X-1116500Y-460800D01*
X-1124200Y-461000D01*
X-1124400Y-461900D01*
X-1117600Y-461800D01*
X-1118800Y-462800D01*
X-1124500Y-462700D01*
X-1124600Y-463600D01*
X-1119300Y-463700D01*
X-1120100Y-464800D01*
X-1125000Y-464600D01*
Y-465500D01*
X-1120600Y-465700D01*
X-1120800Y-466700D01*
X-1125300Y-466500D01*
X-1125500Y-467400D01*
X-1121000Y-467600D01*
X-1121200Y-468700D01*
X-1125600Y-468400D01*
X-1125900Y-469100D01*
X-1121500Y-469500D01*
X-1121700Y-470700D01*
X-1126100Y-470000D01*
X-1126200Y-470700D01*
X-1121900Y-471200D01*
X-1122100Y-472000D01*
X-1126300Y-471700D01*
X-1126700Y-472300D01*
X-1122100Y-472700D01*
X-1122200Y-473100D01*
X-1126800Y-473200D01*
G01X-1114060Y-460760D02*
X-1114840Y-460920D01*
X-1115740Y-461140D01*
X-1116880Y-461820D01*
X-1117700Y-462640D01*
X-1118620Y-463340D01*
X-1118840Y-464020D01*
X-1119440Y-464820D01*
X-1119660Y-465480D01*
X-1120060Y-466280D01*
X-1120280Y-466960D01*
X-1120480Y-468360D01*
X-1120680Y-468940D01*
X-1120880Y-469940D01*
X-1121080Y-470540D01*
X-1121700Y-472980D01*
X-1121820Y-473900D01*
X-1127640D01*
X-1126920Y-471060D01*
X-1126720Y-470440D01*
X-1126500Y-468800D01*
X-1126320Y-467860D01*
X-1126120Y-467260D01*
X-1125920Y-466260D01*
X-1125720Y-465660D01*
X-1125300Y-464000D01*
X-1125120Y-462220D01*
X-1124920Y-461660D01*
X-1124720Y-460660D01*
X-1124520Y-460060D01*
X-1123720Y-456800D01*
X-1123580Y-455700D01*
X-1117880D01*
X-1118100Y-456160D01*
Y-458740D01*
X-1116500Y-457160D01*
X-1115780Y-456620D01*
X-1114680Y-456060D01*
X-1113560Y-455680D01*
X-1112460Y-455500D01*
X-1111720D01*
X-1112460Y-458440D01*
X-1114060Y-460760D01*
G01X-1123100Y-456500D02*
X-1118900Y-456600D01*
X-1118800Y-457600D01*
X-1123100Y-457500D01*
X-1123300Y-458500D01*
X-1113100Y-458400D01*
X-1112600Y-456400D01*
X-1116100Y-457600D01*
X-1113500D01*
G01X-1105100Y-471100D02*
X-1104060D01*
X-1103780Y-470820D01*
X-1103200Y-470640D01*
X-1102080Y-469740D01*
X-1100800Y-468240D01*
X-1100380Y-467400D01*
X-1100180Y-467100D01*
X-1099960Y-466660D01*
X-1099540Y-465720D01*
X-1099320Y-465060D01*
X-1099100Y-464180D01*
Y-461220D01*
X-1099360Y-460200D01*
X-1099660Y-459900D01*
X-1100700Y-458640D01*
X-1101220Y-458300D01*
X-1103340D01*
X-1103700Y-458640D01*
X-1105300Y-459840D01*
X-1105760Y-460320D01*
X-1106180Y-460940D01*
X-1107060Y-462020D01*
X-1107260Y-462880D01*
X-1107660Y-463660D01*
X-1108100Y-465000D01*
Y-468640D01*
X-1107620Y-469600D01*
X-1107140Y-470340D01*
X-1105980Y-471100D01*
X-1105100D01*
G01X-1112540Y-460460D02*
X-1110680Y-458140D01*
X-1109940Y-457580D01*
X-1109000Y-456840D01*
X-1108480Y-456660D01*
X-1107940Y-456400D01*
X-1107740Y-456200D01*
X-1107480Y-456060D01*
X-1106880Y-455860D01*
X-1106480Y-455660D01*
X-1105960Y-455480D01*
X-1104600Y-455300D01*
X-1103440Y-455100D01*
X-1100940D01*
X-1098240Y-455480D01*
X-1097720Y-455660D01*
X-1097020Y-456020D01*
X-1096180Y-456640D01*
X-1095620Y-456820D01*
X-1095540Y-456900D01*
X-1094200Y-458440D01*
X-1093660Y-459520D01*
X-1093460Y-460100D01*
X-1093100Y-461020D01*
Y-464400D01*
X-1093420Y-465360D01*
X-1094300Y-465520D01*
X-1094720Y-465740D01*
X-1095320Y-465940D01*
X-1096120Y-466340D01*
X-1096720Y-466540D01*
X-1097100Y-466720D01*
X-1098100Y-466920D01*
X-1098520Y-467140D01*
X-1099160Y-467360D01*
X-1101180Y-468700D01*
X-1094660D01*
X-1095220Y-469800D01*
X-1095560Y-470320D01*
X-1097480Y-472220D01*
X-1099940Y-473740D01*
X-1102580Y-474500D01*
X-1108800D01*
X-1109300Y-474340D01*
X-1111220Y-473560D01*
X-1111720Y-473240D01*
X-1113240Y-471720D01*
X-1113560Y-471240D01*
X-1113760Y-470660D01*
X-1114140Y-469980D01*
X-1114320Y-469120D01*
X-1114500Y-468680D01*
Y-464980D01*
X-1114320Y-464260D01*
X-1114140Y-463720D01*
X-1113940Y-463320D01*
X-1113720Y-462660D01*
X-1113560Y-462000D01*
X-1111880Y-460320D01*
X-1112540Y-460460D01*
G01X-1099300Y-466400D02*
X-1093800Y-464400D01*
X-1093900Y-461100D01*
X-1094800Y-459000D01*
X-1096800Y-457300D01*
X-1100000Y-456100D01*
X-1102800Y-455900D01*
X-1106300Y-456300D01*
X-1109600Y-458100D01*
X-1111400Y-460500D01*
X-1112900Y-462600D01*
X-1113600Y-465600D01*
X-1113500Y-469100D01*
X-1112100Y-471900D01*
X-1109600Y-473300D01*
X-1105700Y-473800D01*
X-1101000Y-473400D01*
X-1098200Y-471800D01*
X-1096600Y-470100D01*
X-1096000Y-469500D01*
X-1100800Y-469700D01*
X-1102300Y-471100D01*
X-1097900Y-470400D01*
X-1100300Y-471800D01*
X-1103200Y-471400D01*
X-1100600Y-472600D01*
X-1103000D01*
X-1103700Y-471900D01*
X-1103400Y-473000D01*
X-1104600Y-471900D01*
X-1106200D01*
X-1104100Y-473100D01*
X-1107200Y-472700D01*
X-1110100Y-472100D01*
X-1111500Y-470900D01*
X-1112600Y-468600D01*
X-1112700Y-466000D01*
X-1112400Y-463700D01*
X-1111400Y-461600D01*
X-1109600Y-459500D01*
X-1108100Y-458200D01*
X-1105900Y-457200D01*
X-1102200Y-456700D01*
X-1099600Y-457300D01*
X-1097000Y-458400D01*
X-1095500Y-459500D01*
X-1094600Y-461900D01*
X-1094500Y-463900D01*
X-1098800Y-465200D01*
X-1098600Y-464000D01*
X-1095100Y-463100D01*
X-1095300Y-462000D01*
X-1098500Y-463000D01*
X-1098600Y-461700D01*
X-1095600Y-461300D01*
X-1095900Y-460200D01*
X-1098400Y-460700D01*
X-1098900Y-459900D01*
X-1096600Y-459400D01*
X-1097100Y-458900D01*
X-1099400Y-459000D01*
X-1098800Y-458500D01*
X-1100600Y-458000D01*
X-1102400Y-457400D01*
X-1104200Y-457500D01*
X-1106200Y-458100D01*
X-1107900Y-459000D01*
X-1110500Y-462200D01*
X-1111800Y-464800D01*
Y-467700D01*
X-1110700Y-470300D01*
X-1108700Y-472000D01*
X-1106600Y-471900D01*
X-1107900Y-470300D01*
X-1108900Y-468700D01*
Y-465500D01*
X-1107900Y-462300D01*
X-1106500Y-459900D01*
X-1104100Y-458200D01*
X-1108000Y-460000D01*
X-1108100Y-461500D01*
X-1108700Y-461200D01*
X-1110300Y-463600D01*
X-1111000Y-466000D01*
X-1110700Y-468100D01*
X-1109500Y-470600D01*
X-1107700Y-471400D01*
X-1109300Y-469100D01*
X-1109800Y-467600D01*
X-1108600Y-462200D01*
X-1110400Y-466800D01*
G01X-1113600Y-460900D02*
X-1112100Y-459000D01*
G01X-1093100Y-469400D02*
X-1087900Y-469700D01*
X-1086500Y-471400D01*
X-1083400Y-472300D01*
X-1081000Y-472000D01*
X-1079300Y-470600D01*
X-1079000Y-468900D01*
X-1079500Y-467700D01*
X-1080300Y-466600D01*
X-1081800Y-466000D01*
X-1083300Y-465500D01*
X-1085300Y-465000D01*
X-1087900Y-464000D01*
X-1089100Y-463200D01*
X-1089800Y-461000D01*
X-1089500Y-459000D01*
X-1088600Y-457700D01*
X-1086500Y-456700D01*
X-1084600Y-456100D01*
X-1081900Y-455900D01*
X-1079900Y-455800D01*
X-1076900Y-456300D01*
X-1075000Y-457000D01*
X-1073700Y-458000D01*
X-1073300Y-459400D01*
X-1077600Y-459500D01*
X-1078100Y-458800D01*
X-1074300Y-458500D01*
X-1074600Y-457800D01*
X-1078200Y-458200D01*
X-1076000Y-457400D01*
X-1079100Y-457700D01*
X-1077100Y-456900D01*
X-1080100Y-457300D01*
X-1079200Y-456600D01*
X-1083100Y-456800D01*
X-1080600Y-457300D01*
X-1083400Y-457700D01*
X-1083600Y-457000D01*
X-1087900Y-458400D01*
X-1084000Y-458100D01*
X-1088600Y-459100D01*
X-1088800Y-461500D01*
X-1087700Y-463600D01*
X-1084400Y-464300D01*
X-1081200Y-465400D01*
X-1078800Y-467300D01*
X-1078300Y-470500D01*
X-1079900Y-472600D01*
X-1083500Y-473300D01*
X-1085600Y-472600D01*
X-1088800Y-470500D01*
X-1092600Y-470200D01*
X-1092100Y-471800D01*
X-1091700Y-471300D01*
X-1089300Y-471500D01*
X-1091300Y-472300D01*
X-1088700Y-471600D01*
X-1084000Y-473500D01*
X-1089100D01*
X-1091000Y-472900D01*
X-1087200Y-472800D01*
X-1082700Y-473700D01*
X-1079000Y-473600D01*
X-1076500Y-472300D01*
X-1074700Y-470600D01*
X-1074300Y-467300D01*
X-1074800Y-465300D01*
X-1078800Y-463600D01*
X-1081600Y-462900D01*
X-1083400Y-462500D01*
X-1084800Y-461500D01*
X-1085000Y-458900D01*
X-1088100Y-459800D01*
X-1087200Y-462700D01*
X-1085000Y-463400D01*
X-1082000Y-464100D01*
X-1079600Y-465100D01*
X-1078200Y-466500D01*
X-1077700Y-468500D01*
X-1077500Y-470100D01*
X-1079200Y-472800D01*
X-1076800Y-471400D01*
X-1075300Y-470000D01*
X-1077300Y-470900D01*
X-1075000Y-468800D01*
X-1075200Y-466100D01*
X-1082700Y-462700D01*
X-1084200Y-462900D01*
X-1086600Y-461800D01*
X-1087200Y-460300D01*
X-1085800Y-459800D01*
X-1086600Y-461000D01*
X-1085300Y-460400D01*
X-1085600Y-461400D01*
X-1076700Y-466500D01*
X-1075900Y-467100D01*
X-1075700Y-468400D01*
X-1076800Y-469500D01*
X-1077800Y-466200D01*
X-1075900Y-468800D01*
G01X-1093780Y-468700D02*
X-1087100D01*
Y-469740D01*
X-1086800Y-470060D01*
X-1086520Y-470600D01*
X-1085820Y-470820D01*
X-1085660Y-471000D01*
X-1085120Y-471260D01*
X-1084400Y-471500D01*
X-1082360D01*
X-1080540Y-470600D01*
X-1080100Y-470140D01*
Y-469780D01*
X-1079840Y-469380D01*
X-1080380Y-467740D01*
X-1081440Y-466940D01*
X-1082560Y-466720D01*
X-1085740Y-465920D01*
X-1086940Y-465520D01*
X-1087600Y-465360D01*
X-1087740Y-465200D01*
X-1088540Y-464800D01*
X-1089140Y-464200D01*
X-1089540Y-464000D01*
X-1089800Y-463740D01*
X-1090000Y-463340D01*
X-1090180Y-463180D01*
X-1090500Y-462200D01*
Y-459800D01*
X-1090320Y-459260D01*
X-1090140Y-458500D01*
X-1090000Y-458260D01*
X-1089000Y-457260D01*
X-1088860Y-456940D01*
X-1085920Y-455480D01*
X-1083620Y-455100D01*
X-1082060Y-454900D01*
X-1080520D01*
X-1078580Y-455100D01*
X-1076240Y-455480D01*
X-1075120Y-455860D01*
X-1074800Y-456020D01*
X-1073680Y-456760D01*
X-1073160Y-457300D01*
X-1072620Y-458020D01*
X-1072500Y-458240D01*
Y-460300D01*
X-1078500D01*
Y-459200D01*
X-1079580Y-458380D01*
X-1080160Y-458100D01*
X-1082380D01*
X-1083280Y-458360D01*
X-1084020Y-458940D01*
X-1084340Y-459900D01*
X-1084060Y-460720D01*
X-1083740Y-461340D01*
X-1081860Y-462280D01*
X-1079400Y-462500D01*
X-1078660Y-462680D01*
X-1078100Y-462860D01*
X-1076500Y-463460D01*
X-1075320Y-463860D01*
X-1075060Y-464000D01*
X-1073820Y-465220D01*
X-1073480Y-466260D01*
X-1073300Y-467160D01*
Y-468420D01*
X-1073860Y-470700D01*
X-1074000Y-470960D01*
X-1075140Y-472300D01*
X-1075280Y-472440D01*
X-1076600Y-473380D01*
X-1077320Y-473740D01*
X-1079600Y-474500D01*
X-1088240D01*
X-1089160Y-474320D01*
X-1089920Y-474120D01*
X-1090860Y-473760D01*
X-1091560Y-473400D01*
X-1092700Y-472460D01*
X-1093180Y-471980D01*
X-1093340Y-471480D01*
X-1093520Y-471100D01*
X-1093700Y-470320D01*
X-1093780Y-468700D01*
G01X-1095100D02*
X-1092800D01*
G01X-1058300Y-469400D02*
X-1055400Y-467100D01*
X-1053900Y-463700D01*
X-1054400Y-461200D01*
X-1055900Y-459900D01*
X-1054800Y-463500D01*
X-1055400Y-463600D01*
X-1054600Y-464500D01*
X-1055700D01*
X-1055400Y-465300D01*
X-1056200Y-466800D01*
G01X-1059300Y-457700D02*
X-1059100Y-455600D01*
X-1055200Y-456300D01*
X-1052700Y-457900D01*
X-1051100Y-460800D01*
X-1050900Y-465200D01*
X-1052900Y-469400D01*
X-1055300Y-471900D01*
X-1059000Y-473500D01*
X-1066000D01*
X-1068000Y-471900D01*
X-1070200Y-468700D01*
X-1070600Y-464500D01*
X-1069000Y-460500D01*
X-1066000Y-457500D01*
X-1063000Y-456500D01*
X-1059200Y-456000D01*
X-1053000Y-458500D01*
X-1052000Y-461500D01*
Y-465700D01*
X-1053400Y-468600D01*
X-1055700Y-471000D01*
X-1058900Y-472600D01*
X-1063700Y-473000D01*
X-1065900Y-473600D01*
X-1068300Y-472900D01*
X-1070600Y-469300D01*
X-1065100Y-472600D01*
X-1060800Y-472200D01*
X-1057200Y-470700D01*
X-1055200Y-469100D01*
X-1053300Y-466500D01*
X-1052500Y-463400D01*
X-1052900Y-460100D01*
X-1057000Y-457400D01*
X-1058700Y-457200D01*
X-1057000Y-458500D01*
X-1055100Y-459800D01*
X-1053800Y-460900D01*
X-1053400Y-463100D01*
X-1053600Y-465600D01*
X-1054800Y-467500D01*
X-1056400Y-469200D01*
X-1058500Y-470200D01*
X-1060200Y-470700D01*
X-1061500Y-471400D01*
X-1063300Y-471600D01*
X-1065400Y-471500D01*
X-1069000Y-469300D01*
X-1069600Y-466400D01*
X-1069700Y-463700D01*
X-1068600Y-461200D01*
X-1066700Y-459200D01*
X-1063900Y-457600D01*
X-1061100Y-457000D01*
X-1059600D01*
X-1060200Y-457500D01*
X-1063300Y-458000D01*
X-1065300Y-459500D01*
X-1066900Y-460600D01*
X-1067900Y-462100D01*
X-1068800Y-464300D01*
X-1068700Y-466900D01*
X-1068200Y-469100D01*
X-1066900Y-470200D01*
X-1064300Y-470900D01*
X-1065700Y-469300D01*
X-1065800Y-465900D01*
X-1065300Y-462900D01*
X-1061200Y-458200D01*
X-1063600Y-458900D01*
X-1066400Y-461300D01*
X-1067800Y-464200D01*
Y-467200D01*
X-1067400Y-469300D01*
X-1066300Y-469700D01*
X-1067100Y-466400D01*
X-1066600Y-463400D01*
X-1064700Y-460000D01*
X-1062600Y-458800D01*
X-1065300Y-461700D01*
X-1066700Y-467400D01*
G01X-1060840Y-455100D02*
X-1057160D01*
X-1055260Y-455480D01*
X-1054740Y-455640D01*
X-1053380Y-456420D01*
X-1052660Y-456800D01*
X-1052020Y-457420D01*
X-1051820Y-458020D01*
X-1051200Y-458660D01*
X-1051000Y-459060D01*
X-1050840Y-459200D01*
X-1050700Y-459780D01*
Y-460140D01*
X-1050400Y-460460D01*
X-1050280Y-460680D01*
X-1050100Y-461740D01*
Y-464240D01*
X-1050280Y-465160D01*
X-1050480Y-465980D01*
X-1050680Y-467120D01*
X-1051220Y-468180D01*
X-1051840Y-469020D01*
X-1052040Y-469600D01*
X-1052740Y-470500D01*
X-1054480Y-472240D01*
X-1055000Y-472580D01*
X-1055420Y-472780D01*
X-1056220Y-473380D01*
X-1056920Y-473740D01*
X-1059380Y-474500D01*
X-1065600D01*
X-1067860Y-473740D01*
X-1068160Y-473600D01*
X-1069500Y-472460D01*
X-1069820Y-472120D01*
X-1070380Y-471200D01*
X-1071140Y-469860D01*
X-1071300Y-469400D01*
Y-464580D01*
X-1071120Y-463880D01*
X-1070740Y-462900D01*
X-1070540Y-462320D01*
X-1069980Y-461000D01*
X-1068840Y-459500D01*
X-1066900Y-457560D01*
X-1066180Y-457020D01*
X-1065400Y-456620D01*
X-1064440Y-456040D01*
X-1063500Y-455660D01*
X-1062940Y-455480D01*
X-1060840Y-455100D01*
G01X-1057800Y-458580D02*
X-1057000Y-459120D01*
X-1056760Y-459840D01*
X-1056340Y-460460D01*
X-1056100Y-461640D01*
Y-463760D01*
X-1056320Y-464860D01*
X-1056720Y-466060D01*
X-1056940Y-466920D01*
X-1057200Y-467460D01*
X-1057640Y-467880D01*
X-1058040Y-468480D01*
X-1059960Y-470420D01*
X-1061020Y-470840D01*
X-1061420Y-471100D01*
X-1062720D01*
X-1063340Y-470840D01*
X-1063860Y-470600D01*
X-1064360Y-470080D01*
X-1064820Y-469400D01*
X-1065100Y-468840D01*
Y-464920D01*
X-1064880Y-464120D01*
X-1064420Y-462780D01*
X-1064160Y-462520D01*
X-1063620Y-461700D01*
X-1063200Y-460840D01*
X-1062500Y-460140D01*
X-1062120Y-459860D01*
X-1061720Y-459360D01*
X-1060600Y-458580D01*
X-1060040Y-458300D01*
X-1058360D01*
X-1057800Y-458580D01*
G01X-1040300Y-459100D02*
X-1041400Y-464800D01*
G01X-1044800Y-458200D02*
X-1041400D01*
X-1044300Y-472700D01*
X-1047400Y-472300D01*
X-1044100Y-458800D01*
X-1042400Y-459100D01*
X-1045100Y-471900D01*
X-1046500D01*
X-1043400Y-459700D01*
X-1045600Y-471500D01*
G01X-1036600Y-449900D02*
X-1036800Y-451300D01*
X-1038600Y-452400D01*
X-1039800Y-456100D01*
X-1033700Y-456500D01*
X-1032300Y-452100D01*
X-1028400Y-452000D01*
X-1028900Y-455400D01*
X-1027200Y-456600D01*
X-1025900Y-456800D01*
X-1026200Y-458200D01*
X-1030000Y-458400D01*
X-1031800Y-468900D01*
X-1030400Y-471700D01*
X-1029400D01*
X-1029600Y-473300D01*
X-1033100Y-473400D01*
X-1036100Y-472800D01*
X-1036200Y-470500D01*
X-1035900Y-467100D01*
X-1034400Y-461400D01*
X-1033800Y-458800D01*
X-1033500Y-458400D01*
X-1035000Y-458200D01*
X-1039600D01*
X-1040800Y-458300D01*
X-1043600Y-473200D01*
X-1048000Y-473000D01*
X-1045100Y-459400D01*
X-1044900Y-458400D01*
X-1048700D01*
X-1048100Y-456600D01*
X-1044900Y-456400D01*
X-1045200Y-457700D01*
X-1047600Y-457500D01*
X-1026500D01*
G01X-1049580Y-459100D02*
X-1048740Y-455700D01*
X-1044900D01*
Y-454780D01*
X-1044720Y-454060D01*
X-1044340Y-452920D01*
X-1043940Y-452120D01*
X-1043740Y-451520D01*
X-1043600Y-451260D01*
X-1042340Y-450000D01*
X-1042080Y-449860D01*
X-1040580Y-449480D01*
X-1039440Y-449300D01*
X-1036140D01*
X-1035440Y-449400D01*
X-1035480Y-449540D01*
X-1035680Y-450360D01*
X-1035880Y-451280D01*
X-1036000Y-451900D01*
X-1036740D01*
X-1037060Y-452200D01*
X-1037860Y-452600D01*
X-1038220Y-452980D01*
X-1038480Y-453740D01*
X-1038960Y-455700D01*
X-1034020D01*
X-1033720Y-455080D01*
X-1033500Y-453400D01*
X-1032940Y-451100D01*
X-1027260D01*
X-1027280Y-451180D01*
X-1027480Y-452780D01*
X-1027860Y-454280D01*
X-1028100Y-454760D01*
Y-455700D01*
X-1024800D01*
X-1024880Y-455940D01*
X-1025080Y-456940D01*
X-1025280Y-457540D01*
X-1025480Y-458560D01*
X-1025620Y-459100D01*
X-1029100D01*
Y-460000D01*
X-1029280Y-460540D01*
X-1029480Y-461540D01*
X-1029680Y-462140D01*
X-1029880Y-462960D01*
X-1030100Y-464000D01*
X-1030280Y-465560D01*
X-1030480Y-466140D01*
X-1030680Y-467140D01*
X-1030880Y-467740D01*
X-1031040Y-468400D01*
X-1031300Y-468660D01*
Y-469800D01*
X-1030300Y-470560D01*
X-1029940Y-470900D01*
X-1028220D01*
X-1028680Y-472780D01*
X-1028880Y-474120D01*
Y-474140D01*
X-1030720Y-474300D01*
X-1032860D01*
X-1034380Y-474120D01*
X-1035860Y-473740D01*
X-1036640Y-473280D01*
X-1036960Y-472660D01*
X-1037100Y-472280D01*
Y-470160D01*
X-1036920Y-469260D01*
X-1036700Y-468640D01*
X-1036500Y-466840D01*
X-1036320Y-466260D01*
X-1036120Y-465260D01*
X-1035920Y-464660D01*
X-1035720Y-463660D01*
X-1035520Y-463060D01*
X-1035320Y-462060D01*
X-1035120Y-461440D01*
X-1034820Y-459100D01*
X-1039900D01*
Y-460220D01*
X-1040280Y-461780D01*
X-1040480Y-463380D01*
X-1041280Y-466540D01*
X-1041480Y-467140D01*
X-1041700Y-468200D01*
X-1041880Y-469760D01*
X-1042080Y-470340D01*
X-1042280Y-471360D01*
X-1042480Y-472140D01*
X-1042680Y-472740D01*
X-1042880Y-473740D01*
X-1042940Y-473900D01*
X-1049140D01*
X-1048300Y-470620D01*
X-1048100Y-469020D01*
X-1047920Y-468260D01*
X-1047720Y-467660D01*
X-1047520Y-466660D01*
X-1047320Y-466060D01*
X-1047120Y-465060D01*
X-1046920Y-464460D01*
X-1046700Y-463400D01*
X-1046500Y-462020D01*
X-1046140Y-460500D01*
X-1045900Y-460040D01*
Y-459100D01*
X-1049580D01*
G01X-1038400Y-451100D02*
X-1040600Y-455800D01*
X-1043300D01*
X-1041400Y-451300D01*
X-1038900Y-451000D01*
X-1041200Y-455000D01*
X-1042000Y-455100D01*
X-1040500Y-452000D01*
G01X-1037500Y-449800D02*
X-1037800Y-451000D01*
X-1038500Y-450100D01*
X-1042000Y-450700D01*
X-1043100Y-452300D01*
X-1044100Y-455100D01*
X-1044200Y-456600D01*
X-1036600Y-456800D01*
G01X-1031100Y-472500D02*
X-1031400Y-470900D01*
X-1031900Y-472200D01*
X-1035200D01*
Y-467600D01*
X-1032000Y-453700D01*
X-1030500Y-453800D01*
X-1030000Y-456700D01*
X-1033400Y-471900D01*
X-1034300Y-471600D01*
X-1034200Y-467100D01*
X-1031400Y-454500D01*
X-1030700Y-456500D01*
X-1033700Y-470600D01*
X-1032700Y-461100D01*
G01X-1032000Y-452900D02*
X-1029300D01*
X-1028000Y-457000D01*
X-1029500Y-453600D01*
X-1029100Y-457300D01*
X-1032800Y-472800D01*
X-1030200Y-472600D01*
M02*
